(kicad_sch
	(version 20250114)
	(generator "eeschema")
	(generator_version "9.0")
	(paper "A3")
	(title_block
		(title "SO-DIMM DDR5 Tester")
		(date "2025-11-26")
		(rev "1.3.0")
		(company "Antmicro Ltd.")
		(comment 1 "www.antmicro.com")
		(comment 2 "Antmicro Ltd")
	)
	(text "Bootstrap configuration"
		(exclude_from_sim no)
		(at 35.56 191.77 0)
		(effects
			(font
				(size 1.27 1.27)
				(thickness 0.5994)
				(bold yes)
			)
			(justify left bottom)
		)
	)
	(text "PHYAD2"
		(exclude_from_sim no)
		(at 83.185 217.17 0)
		(effects
			(font
				(size 1.27 1.27)
			)
			(justify left bottom)
		)
	)
	(text "CLK125_EN"
		(exclude_from_sim no)
		(at 82.55 225.425 0)
		(effects
			(font
				(size 1.27 1.27)
			)
			(justify left bottom)
		)
	)
	(text "MODE2"
		(exclude_from_sim no)
		(at 83.185 208.28 0)
		(effects
			(font
				(size 1.27 1.27)
			)
			(justify left bottom)
		)
	)
	(text "Reference plane decoupling"
		(exclude_from_sim no)
		(at 263.525 253.365 0)
		(effects
			(font
				(size 1.27 1.27)
			)
			(justify left bottom)
		)
	)
	(text "PHYAD1"
		(exclude_from_sim no)
		(at 83.185 219.71 0)
		(effects
			(font
				(size 1.27 1.27)
			)
			(justify left bottom)
		)
	)
	(text "MODE[3:0] : 1100 (RGMII mode - Advertise 1000BASE-T full-duplex only)\nPHYAD[4:0]: 00011 \nCLK125_EN: 0, disabled\nLED_MODE: 1,  Single-LED mode\n"
		(exclude_from_sim no)
		(at 30.48 245.745 0)
		(effects
			(font
				(size 1.27 1.27)
			)
			(justify left bottom)
		)
	)
	(text "Gigabit Ethernet"
		(exclude_from_sim no)
		(at 13.335 17.78 0)
		(effects
			(font
				(size 2.54 2.54)
				(thickness 0.4)
				(bold yes)
			)
			(justify left bottom)
		)
	)
	(text "MODE3"
		(exclude_from_sim no)
		(at 83.185 205.74 0)
		(effects
			(font
				(size 1.27 1.27)
			)
			(justify left bottom)
		)
	)
	(text "MODE1"
		(exclude_from_sim no)
		(at 83.185 210.82 0)
		(effects
			(font
				(size 1.27 1.27)
			)
			(justify left bottom)
		)
	)
	(text "MODE0\n"
		(exclude_from_sim no)
		(at 83.185 213.36 0)
		(effects
			(font
				(size 1.27 1.27)
			)
			(justify left bottom)
		)
	)
	(text "LED_MODE"
		(exclude_from_sim no)
		(at 82.55 227.965 0)
		(effects
			(font
				(size 1.27 1.27)
			)
			(justify left bottom)
		)
	)
	(text "PHYAD0"
		(exclude_from_sim no)
		(at 83.185 222.25 0)
		(effects
			(font
				(size 1.27 1.27)
			)
			(justify left bottom)
		)
	)
	(junction
		(at 207.01 53.975)
		(diameter 0)
		(color 0 0 0 0)
	)
	(junction
		(at 45.085 222.25)
		(diameter 0)
		(color 0 0 0 0)
	)
	(junction
		(at 112.395 69.85)
		(diameter 0)
		(color 0 0 0 0)
	)
	(junction
		(at 120.65 69.85)
		(diameter 0)
		(color 0 0 0 0)
	)
	(junction
		(at 45.085 217.17)
		(diameter 0)
		(color 0 0 0 0)
	)
	(junction
		(at 45.085 213.995)
		(diameter 0)
		(color 0 0 0 0)
	)
	(junction
		(at 207.01 75.565)
		(diameter 0)
		(color 0 0 0 0)
	)
	(junction
		(at 256.54 53.975)
		(diameter 0)
		(color 0 0 0 0)
	)
	(junction
		(at 260.985 75.565)
		(diameter 0)
		(color 0 0 0 0)
	)
	(junction
		(at 86.36 92.71)
		(diameter 0)
		(color 0 0 0 0)
	)
	(junction
		(at 260.985 53.975)
		(diameter 0)
		(color 0 0 0 0)
	)
	(junction
		(at 109.22 144.78)
		(diameter 0)
		(color 0 0 0 0)
	)
	(junction
		(at 244.475 91.44)
		(diameter 0)
		(color 0 0 0 0)
	)
	(junction
		(at 116.84 213.995)
		(diameter 0)
		(color 0 0 0 0)
	)
	(junction
		(at 45.085 208.915)
		(diameter 0)
		(color 0 0 0 0)
	)
	(junction
		(at 79.375 48.895)
		(diameter 0)
		(color 0 0 0 0)
	)
	(junction
		(at 121.92 153.67)
		(diameter 0)
		(color 0 0 0 0)
	)
	(junction
		(at 45.085 211.455)
		(diameter 0)
		(color 0 0 0 0)
	)
	(junction
		(at 116.84 211.455)
		(diameter 0)
		(color 0 0 0 0)
	)
	(junction
		(at 95.885 48.895)
		(diameter 0)
		(color 0 0 0 0)
	)
	(junction
		(at 198.755 75.565)
		(diameter 0)
		(color 0 0 0 0)
	)
	(junction
		(at 109.22 153.67)
		(diameter 0)
		(color 0 0 0 0)
	)
	(junction
		(at 273.05 138.43)
		(diameter 0)
		(color 0 0 0 0)
	)
	(junction
		(at 198.755 91.44)
		(diameter 0)
		(color 0 0 0 0)
	)
	(junction
		(at 243.84 75.565)
		(diameter 0)
		(color 0 0 0 0)
	)
	(junction
		(at 116.84 219.71)
		(diameter 0)
		(color 0 0 0 0)
	)
	(junction
		(at 190.5 75.565)
		(diameter 0)
		(color 0 0 0 0)
	)
	(junction
		(at 116.84 208.915)
		(diameter 0)
		(color 0 0 0 0)
	)
	(junction
		(at 190.5 53.975)
		(diameter 0)
		(color 0 0 0 0)
	)
	(junction
		(at 112.395 48.895)
		(diameter 0)
		(color 0 0 0 0)
	)
	(junction
		(at 284.48 151.13)
		(diameter 0)
		(color 0 0 0 0)
	)
	(junction
		(at 45.085 225.425)
		(diameter 0)
		(color 0 0 0 0)
	)
	(junction
		(at 74.295 48.895)
		(diameter 0)
		(color 0 0 0 0)
	)
	(junction
		(at 45.085 206.375)
		(diameter 0)
		(color 0 0 0 0)
	)
	(junction
		(at 104.14 69.85)
		(diameter 0)
		(color 0 0 0 0)
	)
	(junction
		(at 87.63 48.895)
		(diameter 0)
		(color 0 0 0 0)
	)
	(junction
		(at 177.165 144.78)
		(diameter 0)
		(color 0 0 0 0)
	)
	(junction
		(at 45.085 219.71)
		(diameter 0)
		(color 0 0 0 0)
	)
	(junction
		(at 248.285 53.975)
		(diameter 0)
		(color 0 0 0 0)
	)
	(junction
		(at 215.265 53.975)
		(diameter 0)
		(color 0 0 0 0)
	)
	(junction
		(at 104.14 48.895)
		(diameter 0)
		(color 0 0 0 0)
	)
	(junction
		(at 198.755 53.975)
		(diameter 0)
		(color 0 0 0 0)
	)
	(junction
		(at 207.01 91.44)
		(diameter 0)
		(color 0 0 0 0)
	)
	(junction
		(at 190.5 91.44)
		(diameter 0)
		(color 0 0 0 0)
	)
	(junction
		(at 215.265 75.565)
		(diameter 0)
		(color 0 0 0 0)
	)
	(junction
		(at 240.03 53.975)
		(diameter 0)
		(color 0 0 0 0)
	)
	(junction
		(at 177.165 142.24)
		(diameter 0)
		(color 0 0 0 0)
	)
	(junction
		(at 231.775 53.975)
		(diameter 0)
		(color 0 0 0 0)
	)
	(junction
		(at 121.92 144.78)
		(diameter 0)
		(color 0 0 0 0)
	)
	(junction
		(at 116.84 225.425)
		(diameter 0)
		(color 0 0 0 0)
	)
	(junction
		(at 115.57 162.56)
		(diameter 0)
		(color 0 0 0 0)
	)
	(junction
		(at 223.52 53.975)
		(diameter 0)
		(color 0 0 0 0)
	)
	(junction
		(at 116.84 227.965)
		(diameter 0)
		(color 0 0 0 0)
	)
	(junction
		(at 95.885 69.85)
		(diameter 0)
		(color 0 0 0 0)
	)
	(junction
		(at 116.84 222.25)
		(diameter 0)
		(color 0 0 0 0)
	)
	(junction
		(at 116.84 217.17)
		(diameter 0)
		(color 0 0 0 0)
	)
	(junction
		(at 288.29 142.24)
		(diameter 0)
		(color 0 0 0 0)
	)
	(no_connect
		(at 175.26 93.98)
	)
	(bus_entry
		(at 116.205 99.06)
		(size -2.54 2.54)
		(stroke
			(width 0)
			(type default)
		)
	)
	(bus_entry
		(at 118.745 92.71)
		(size -2.54 -2.54)
		(stroke
			(width 0)
			(type default)
		)
	)
	(bus_entry
		(at 118.745 134.62)
		(size -2.54 -2.54)
		(stroke
			(width 0)
			(type default)
		)
	)
	(bus_entry
		(at 118.745 118.11)
		(size -2.54 -2.54)
		(stroke
			(width 0)
			(type default)
		)
	)
	(bus_entry
		(at 118.745 113.03)
		(size -2.54 -2.54)
		(stroke
			(width 0)
			(type default)
		)
	)
	(bus_entry
		(at 118.745 121.92)
		(size -2.54 -2.54)
		(stroke
			(width 0)
			(type default)
		)
	)
	(bus_entry
		(at 116.205 90.17)
		(size -2.54 2.54)
		(stroke
			(width 0)
			(type default)
		)
	)
	(bus_entry
		(at 118.745 95.25)
		(size -2.54 -2.54)
		(stroke
			(width 0)
			(type default)
		)
	)
	(bus_entry
		(at 118.745 107.95)
		(size -2.54 -2.54)
		(stroke
			(width 0)
			(type default)
		)
	)
	(bus_entry
		(at 118.745 132.08)
		(size -2.54 -2.54)
		(stroke
			(width 0)
			(type default)
		)
	)
	(bus_entry
		(at 118.745 124.46)
		(size -2.54 -2.54)
		(stroke
			(width 0)
			(type default)
		)
	)
	(bus_entry
		(at 118.745 115.57)
		(size -2.54 -2.54)
		(stroke
			(width 0)
			(type default)
		)
	)
	(bus_entry
		(at 118.745 99.06)
		(size -2.54 -2.54)
		(stroke
			(width 0)
			(type default)
		)
	)
	(bus_entry
		(at 118.745 105.41)
		(size -2.54 -2.54)
		(stroke
			(width 0)
			(type default)
		)
	)
	(bus_entry
		(at 118.745 138.43)
		(size -2.54 -2.54)
		(stroke
			(width 0)
			(type default)
		)
	)
	(bus_entry
		(at 118.745 110.49)
		(size -2.54 -2.54)
		(stroke
			(width 0)
			(type default)
		)
	)
	(bus_entry
		(at 118.745 127)
		(size -2.54 -2.54)
		(stroke
			(width 0)
			(type default)
		)
	)
	(bus_entry
		(at 118.745 101.6)
		(size -2.54 -2.54)
		(stroke
			(width 0)
			(type default)
		)
	)
	(bus_entry
		(at 118.745 129.54)
		(size -2.54 -2.54)
		(stroke
			(width 0)
			(type default)
		)
	)
	(wire
		(pts
			(xy 121.92 162.56) (xy 115.57 162.56)
		)
		(stroke
			(width 0)
			(type default)
		)
	)
	(wire
		(pts
			(xy 207.01 82.55) (xy 207.01 83.82)
		)
		(stroke
			(width 0)
			(type default)
		)
	)
	(bus
		(pts
			(xy 116.205 99.06) (xy 116.205 102.87)
		)
		(stroke
			(width 0)
			(type default)
		)
	)
	(wire
		(pts
			(xy 56.515 211.455) (xy 45.085 211.455)
		)
		(stroke
			(width 0)
			(type default)
		)
	)
	(wire
		(pts
			(xy 183.515 114.3) (xy 175.26 114.3)
		)
		(stroke
			(width 0)
			(type default)
		)
	)
	(wire
		(pts
			(xy 284.48 142.24) (xy 284.48 144.78)
		)
		(stroke
			(width 0)
			(type default)
		)
	)
	(wire
		(pts
			(xy 106.045 208.915) (xy 116.84 208.915)
		)
		(stroke
			(width 0)
			(type default)
		)
	)
	(wire
		(pts
			(xy 312.42 142.24) (xy 330.2 142.24)
		)
		(stroke
			(width 0)
			(type default)
		)
	)
	(wire
		(pts
			(xy 74.295 69.85) (xy 74.295 48.895)
		)
		(stroke
			(width 0)
			(type default)
		)
	)
	(wire
		(pts
			(xy 56.515 208.915) (xy 45.085 208.915)
		)
		(stroke
			(width 0)
			(type default)
		)
	)
	(bus
		(pts
			(xy 116.205 92.71) (xy 116.205 96.52)
		)
		(stroke
			(width 0)
			(type default)
		)
	)
	(wire
		(pts
			(xy 175.26 91.44) (xy 190.5 91.44)
		)
		(stroke
			(width 0)
			(type default)
		)
	)
	(wire
		(pts
			(xy 288.29 149.86) (xy 288.29 151.13)
		)
		(stroke
			(width 0)
			(type default)
		)
	)
	(wire
		(pts
			(xy 112.395 69.85) (xy 104.14 69.85)
		)
		(stroke
			(width 0)
			(type default)
		)
	)
	(wire
		(pts
			(xy 121.92 144.78) (xy 121.92 153.67)
		)
		(stroke
			(width 0)
			(type default)
		)
	)
	(wire
		(pts
			(xy 280.67 119.38) (xy 289.56 119.38)
		)
		(stroke
			(width 0)
			(type default)
		)
	)
	(bus
		(pts
			(xy 116.205 107.95) (xy 116.205 110.49)
		)
		(stroke
			(width 0)
			(type default)
		)
	)
	(wire
		(pts
			(xy 130.81 107.95) (xy 118.745 107.95)
		)
		(stroke
			(width 0)
			(type default)
		)
	)
	(wire
		(pts
			(xy 87.63 48.895) (xy 87.63 51.435)
		)
		(stroke
			(width 0)
			(type default)
		)
	)
	(wire
		(pts
			(xy 130.81 88.9) (xy 120.65 88.9)
		)
		(stroke
			(width 0)
			(type default)
		)
	)
	(wire
		(pts
			(xy 312.42 139.7) (xy 316.23 139.7)
		)
		(stroke
			(width 0)
			(type default)
		)
	)
	(wire
		(pts
			(xy 215.265 77.47) (xy 215.265 75.565)
		)
		(stroke
			(width 0)
			(type default)
		)
	)
	(wire
		(pts
			(xy 321.31 139.7) (xy 327.66 139.7)
		)
		(stroke
			(width 0)
			(type default)
		)
	)
	(wire
		(pts
			(xy 45.085 225.425) (xy 45.085 227.965)
		)
		(stroke
			(width 0)
			(type default)
		)
	)
	(wire
		(pts
			(xy 118.745 92.71) (xy 130.81 92.71)
		)
		(stroke
			(width 0)
			(type default)
		)
	)
	(wire
		(pts
			(xy 223.52 61.595) (xy 223.52 62.865)
		)
		(stroke
			(width 0)
			(type default)
		)
	)
	(wire
		(pts
			(xy 190.5 91.44) (xy 190.5 93.345)
		)
		(stroke
			(width 0)
			(type default)
		)
	)
	(wire
		(pts
			(xy 215.265 82.55) (xy 215.265 83.82)
		)
		(stroke
			(width 0)
			(type default)
		)
	)
	(bus
		(pts
			(xy 116.205 96.52) (xy 116.205 99.06)
		)
		(stroke
			(width 0)
			(type default)
		)
	)
	(wire
		(pts
			(xy 240.03 61.595) (xy 240.03 62.865)
		)
		(stroke
			(width 0)
			(type default)
		)
	)
	(wire
		(pts
			(xy 183.515 120.65) (xy 175.26 120.65)
		)
		(stroke
			(width 0)
			(type default)
		)
	)
	(wire
		(pts
			(xy 95.885 77.47) (xy 95.885 78.74)
		)
		(stroke
			(width 0)
			(type default)
		)
	)
	(wire
		(pts
			(xy 56.515 206.375) (xy 45.085 206.375)
		)
		(stroke
			(width 0)
			(type default)
		)
	)
	(wire
		(pts
			(xy 61.595 225.425) (xy 100.965 225.425)
		)
		(stroke
			(width 0)
			(type default)
		)
	)
	(wire
		(pts
			(xy 183.515 111.76) (xy 175.26 111.76)
		)
		(stroke
			(width 0)
			(type default)
		)
	)
	(wire
		(pts
			(xy 109.22 153.67) (xy 111.76 153.67)
		)
		(stroke
			(width 0)
			(type default)
		)
	)
	(wire
		(pts
			(xy 45.085 211.455) (xy 45.085 213.995)
		)
		(stroke
			(width 0)
			(type default)
		)
	)
	(wire
		(pts
			(xy 106.045 206.375) (xy 116.84 206.375)
		)
		(stroke
			(width 0)
			(type default)
		)
	)
	(wire
		(pts
			(xy 223.52 53.975) (xy 223.52 56.515)
		)
		(stroke
			(width 0)
			(type default)
		)
	)
	(wire
		(pts
			(xy 97.155 101.6) (xy 113.665 101.6)
		)
		(stroke
			(width 0)
			(type default)
		)
	)
	(wire
		(pts
			(xy 119.38 153.67) (xy 121.92 153.67)
		)
		(stroke
			(width 0)
			(type default)
		)
	)
	(wire
		(pts
			(xy 118.745 127) (xy 130.81 127)
		)
		(stroke
			(width 0)
			(type default)
		)
	)
	(wire
		(pts
			(xy 79.375 48.895) (xy 79.375 51.435)
		)
		(stroke
			(width 0)
			(type default)
		)
	)
	(wire
		(pts
			(xy 61.595 217.17) (xy 100.965 217.17)
		)
		(stroke
			(width 0)
			(type default)
		)
	)
	(wire
		(pts
			(xy 106.045 219.71) (xy 116.84 219.71)
		)
		(stroke
			(width 0)
			(type default)
		)
	)
	(wire
		(pts
			(xy 112.395 48.895) (xy 128.905 48.895)
		)
		(stroke
			(width 0)
			(type default)
		)
	)
	(bus
		(pts
			(xy 113.665 88.265) (xy 115.57 88.265)
		)
		(stroke
			(width 0)
			(type default)
		)
	)
	(wire
		(pts
			(xy 273.05 138.43) (xy 278.13 138.43)
		)
		(stroke
			(width 0)
			(type default)
		)
	)
	(wire
		(pts
			(xy 112.395 69.85) (xy 120.65 69.85)
		)
		(stroke
			(width 0)
			(type default)
		)
	)
	(wire
		(pts
			(xy 121.92 144.78) (xy 130.81 144.78)
		)
		(stroke
			(width 0)
			(type default)
		)
	)
	(wire
		(pts
			(xy 128.905 85.09) (xy 130.81 85.09)
		)
		(stroke
			(width 0)
			(type default)
		)
	)
	(wire
		(pts
			(xy 104.14 69.85) (xy 95.885 69.85)
		)
		(stroke
			(width 0)
			(type default)
		)
	)
	(wire
		(pts
			(xy 56.515 225.425) (xy 45.085 225.425)
		)
		(stroke
			(width 0)
			(type default)
		)
	)
	(wire
		(pts
			(xy 130.81 129.54) (xy 118.745 129.54)
		)
		(stroke
			(width 0)
			(type default)
		)
	)
	(wire
		(pts
			(xy 257.81 91.44) (xy 260.985 91.44)
		)
		(stroke
			(width 0)
			(type default)
		)
	)
	(wire
		(pts
			(xy 116.84 211.455) (xy 116.84 213.995)
		)
		(stroke
			(width 0)
			(type default)
		)
	)
	(wire
		(pts
			(xy 256.54 53.975) (xy 260.985 53.975)
		)
		(stroke
			(width 0)
			(type default)
		)
	)
	(wire
		(pts
			(xy 77.47 69.85) (xy 74.295 69.85)
		)
		(stroke
			(width 0)
			(type default)
		)
	)
	(wire
		(pts
			(xy 95.885 69.85) (xy 82.55 69.85)
		)
		(stroke
			(width 0)
			(type default)
		)
	)
	(wire
		(pts
			(xy 284.48 151.13) (xy 284.48 152.4)
		)
		(stroke
			(width 0)
			(type default)
		)
	)
	(wire
		(pts
			(xy 283.21 138.43) (xy 289.56 138.43)
		)
		(stroke
			(width 0)
			(type default)
		)
	)
	(wire
		(pts
			(xy 198.755 75.565) (xy 207.01 75.565)
		)
		(stroke
			(width 0)
			(type default)
		)
	)
	(wire
		(pts
			(xy 327.66 138.43) (xy 327.66 139.7)
		)
		(stroke
			(width 0)
			(type default)
		)
	)
	(wire
		(pts
			(xy 118.745 132.08) (xy 130.81 132.08)
		)
		(stroke
			(width 0)
			(type default)
		)
	)
	(wire
		(pts
			(xy 190.5 53.975) (xy 198.755 53.975)
		)
		(stroke
			(width 0)
			(type default)
		)
	)
	(wire
		(pts
			(xy 92.075 101.6) (xy 86.36 101.6)
		)
		(stroke
			(width 0)
			(type default)
		)
	)
	(wire
		(pts
			(xy 115.57 158.75) (xy 115.57 162.56)
		)
		(stroke
			(width 0)
			(type default)
		)
	)
	(wire
		(pts
			(xy 280.67 129.54) (xy 289.56 129.54)
		)
		(stroke
			(width 0)
			(type default)
		)
	)
	(wire
		(pts
			(xy 130.81 124.46) (xy 118.745 124.46)
		)
		(stroke
			(width 0)
			(type default)
		)
	)
	(wire
		(pts
			(xy 184.785 129.54) (xy 175.26 129.54)
		)
		(stroke
			(width 0)
			(type default)
		)
	)
	(bus
		(pts
			(xy 116.205 88.9) (xy 116.205 90.17)
		)
		(stroke
			(width 0)
			(type default)
		)
	)
	(wire
		(pts
			(xy 86.36 90.805) (xy 86.36 92.71)
		)
		(stroke
			(width 0)
			(type default)
		)
	)
	(wire
		(pts
			(xy 198.755 91.44) (xy 198.755 93.345)
		)
		(stroke
			(width 0)
			(type default)
		)
	)
	(wire
		(pts
			(xy 260.985 52.07) (xy 260.985 53.975)
		)
		(stroke
			(width 0)
			(type default)
		)
	)
	(wire
		(pts
			(xy 56.515 222.25) (xy 45.085 222.25)
		)
		(stroke
			(width 0)
			(type default)
		)
	)
	(wire
		(pts
			(xy 104.14 56.515) (xy 104.14 57.785)
		)
		(stroke
			(width 0)
			(type default)
		)
	)
	(wire
		(pts
			(xy 112.395 48.895) (xy 104.14 48.895)
		)
		(stroke
			(width 0)
			(type default)
		)
	)
	(wire
		(pts
			(xy 183.515 118.11) (xy 175.26 118.11)
		)
		(stroke
			(width 0)
			(type default)
		)
	)
	(wire
		(pts
			(xy 106.045 213.995) (xy 116.84 213.995)
		)
		(stroke
			(width 0)
			(type default)
		)
	)
	(wire
		(pts
			(xy 45.085 204.47) (xy 45.085 206.375)
		)
		(stroke
			(width 0)
			(type default)
		)
	)
	(wire
		(pts
			(xy 56.515 227.965) (xy 45.085 227.965)
		)
		(stroke
			(width 0)
			(type default)
		)
	)
	(wire
		(pts
			(xy 185.42 75.565) (xy 190.5 75.565)
		)
		(stroke
			(width 0)
			(type default)
		)
	)
	(bus
		(pts
			(xy 116.205 132.08) (xy 116.205 135.89)
		)
		(stroke
			(width 0)
			(type default)
		)
	)
	(wire
		(pts
			(xy 207.01 75.565) (xy 207.01 77.47)
		)
		(stroke
			(width 0)
			(type default)
		)
	)
	(wire
		(pts
			(xy 116.84 225.425) (xy 116.84 227.965)
		)
		(stroke
			(width 0)
			(type default)
		)
	)
	(wire
		(pts
			(xy 177.165 144.78) (xy 177.165 146.685)
		)
		(stroke
			(width 0)
			(type default)
		)
	)
	(wire
		(pts
			(xy 175.26 88.9) (xy 185.42 88.9)
		)
		(stroke
			(width 0)
			(type default)
		)
	)
	(wire
		(pts
			(xy 248.285 53.975) (xy 256.54 53.975)
		)
		(stroke
			(width 0)
			(type default)
		)
	)
	(wire
		(pts
			(xy 45.085 217.17) (xy 45.085 219.71)
		)
		(stroke
			(width 0)
			(type default)
		)
	)
	(bus
		(pts
			(xy 116.205 90.17) (xy 116.205 92.71)
		)
		(stroke
			(width 0)
			(type default)
		)
	)
	(wire
		(pts
			(xy 116.84 219.71) (xy 116.84 222.25)
		)
		(stroke
			(width 0)
			(type default)
		)
	)
	(wire
		(pts
			(xy 61.595 211.455) (xy 100.965 211.455)
		)
		(stroke
			(width 0)
			(type default)
		)
	)
	(wire
		(pts
			(xy 56.515 219.71) (xy 45.085 219.71)
		)
		(stroke
			(width 0)
			(type default)
		)
	)
	(bus
		(pts
			(xy 116.205 121.92) (xy 116.205 124.46)
		)
		(stroke
			(width 0)
			(type default)
		)
	)
	(wire
		(pts
			(xy 280.67 121.92) (xy 289.56 121.92)
		)
		(stroke
			(width 0)
			(type default)
		)
	)
	(wire
		(pts
			(xy 61.595 208.915) (xy 100.965 208.915)
		)
		(stroke
			(width 0)
			(type default)
		)
	)
	(wire
		(pts
			(xy 104.14 77.47) (xy 104.14 78.74)
		)
		(stroke
			(width 0)
			(type default)
		)
	)
	(wire
		(pts
			(xy 109.22 144.78) (xy 113.03 144.78)
		)
		(stroke
			(width 0)
			(type default)
		)
	)
	(wire
		(pts
			(xy 185.42 88.9) (xy 185.42 75.565)
		)
		(stroke
			(width 0)
			(type default)
		)
	)
	(wire
		(pts
			(xy 198.755 53.975) (xy 198.755 56.515)
		)
		(stroke
			(width 0)
			(type default)
		)
	)
	(wire
		(pts
			(xy 118.745 138.43) (xy 130.81 138.43)
		)
		(stroke
			(width 0)
			(type default)
		)
	)
	(wire
		(pts
			(xy 183.515 101.6) (xy 175.26 101.6)
		)
		(stroke
			(width 0)
			(type default)
		)
	)
	(wire
		(pts
			(xy 288.29 142.24) (xy 289.56 142.24)
		)
		(stroke
			(width 0)
			(type default)
		)
	)
	(bus
		(pts
			(xy 116.205 115.57) (xy 116.205 119.38)
		)
		(stroke
			(width 0)
			(type default)
		)
	)
	(wire
		(pts
			(xy 248.285 61.595) (xy 248.285 62.865)
		)
		(stroke
			(width 0)
			(type default)
		)
	)
	(wire
		(pts
			(xy 190.5 98.425) (xy 190.5 99.695)
		)
		(stroke
			(width 0)
			(type default)
		)
	)
	(wire
		(pts
			(xy 113.665 92.71) (xy 97.155 92.71)
		)
		(stroke
			(width 0)
			(type default)
		)
	)
	(wire
		(pts
			(xy 109.22 142.24) (xy 130.81 142.24)
		)
		(stroke
			(width 0)
			(type default)
		)
	)
	(wire
		(pts
			(xy 130.81 101.6) (xy 118.745 101.6)
		)
		(stroke
			(width 0)
			(type default)
		)
	)
	(wire
		(pts
			(xy 190.5 53.975) (xy 190.5 56.515)
		)
		(stroke
			(width 0)
			(type default)
		)
	)
	(wire
		(pts
			(xy 106.045 211.455) (xy 116.84 211.455)
		)
		(stroke
			(width 0)
			(type default)
		)
	)
	(wire
		(pts
			(xy 207.01 61.595) (xy 207.01 62.865)
		)
		(stroke
			(width 0)
			(type default)
		)
	)
	(wire
		(pts
			(xy 121.92 153.67) (xy 121.92 154.94)
		)
		(stroke
			(width 0)
			(type default)
		)
	)
	(wire
		(pts
			(xy 198.755 82.55) (xy 198.755 83.82)
		)
		(stroke
			(width 0)
			(type default)
		)
	)
	(wire
		(pts
			(xy 256.54 53.975) (xy 256.54 56.515)
		)
		(stroke
			(width 0)
			(type default)
		)
	)
	(wire
		(pts
			(xy 244.475 91.44) (xy 252.73 91.44)
		)
		(stroke
			(width 0)
			(type default)
		)
	)
	(wire
		(pts
			(xy 207.01 53.975) (xy 207.01 56.515)
		)
		(stroke
			(width 0)
			(type default)
		)
	)
	(wire
		(pts
			(xy 87.63 48.895) (xy 79.375 48.895)
		)
		(stroke
			(width 0)
			(type default)
		)
	)
	(wire
		(pts
			(xy 61.595 219.71) (xy 100.965 219.71)
		)
		(stroke
			(width 0)
			(type default)
		)
	)
	(wire
		(pts
			(xy 116.84 222.25) (xy 116.84 225.425)
		)
		(stroke
			(width 0)
			(type default)
		)
	)
	(wire
		(pts
			(xy 130.81 118.11) (xy 118.745 118.11)
		)
		(stroke
			(width 0)
			(type default)
		)
	)
	(wire
		(pts
			(xy 215.265 53.975) (xy 215.265 56.515)
		)
		(stroke
			(width 0)
			(type default)
		)
	)
	(bus
		(pts
			(xy 116.205 105.41) (xy 116.205 107.95)
		)
		(stroke
			(width 0)
			(type default)
		)
	)
	(wire
		(pts
			(xy 280.67 114.3) (xy 289.56 114.3)
		)
		(stroke
			(width 0)
			(type default)
		)
	)
	(wire
		(pts
			(xy 116.84 208.915) (xy 116.84 211.455)
		)
		(stroke
			(width 0)
			(type default)
		)
	)
	(wire
		(pts
			(xy 198.755 77.47) (xy 198.755 75.565)
		)
		(stroke
			(width 0)
			(type default)
		)
	)
	(wire
		(pts
			(xy 215.265 61.595) (xy 215.265 62.865)
		)
		(stroke
			(width 0)
			(type default)
		)
	)
	(wire
		(pts
			(xy 177.165 142.24) (xy 177.165 144.78)
		)
		(stroke
			(width 0)
			(type default)
		)
	)
	(wire
		(pts
			(xy 74.295 46.99) (xy 74.295 48.895)
		)
		(stroke
			(width 0)
			(type default)
		)
	)
	(wire
		(pts
			(xy 190.5 61.595) (xy 190.5 62.865)
		)
		(stroke
			(width 0)
			(type default)
		)
	)
	(wire
		(pts
			(xy 207.01 98.425) (xy 207.01 99.695)
		)
		(stroke
			(width 0)
			(type default)
		)
	)
	(wire
		(pts
			(xy 95.885 48.895) (xy 95.885 51.435)
		)
		(stroke
			(width 0)
			(type default)
		)
	)
	(wire
		(pts
			(xy 273.05 138.43) (xy 273.05 140.97)
		)
		(stroke
			(width 0)
			(type default)
		)
	)
	(wire
		(pts
			(xy 177.8 53.975) (xy 177.8 85.09)
		)
		(stroke
			(width 0)
			(type default)
		)
	)
	(wire
		(pts
			(xy 284.48 149.86) (xy 284.48 151.13)
		)
		(stroke
			(width 0)
			(type default)
		)
	)
	(wire
		(pts
			(xy 61.595 206.375) (xy 100.965 206.375)
		)
		(stroke
			(width 0)
			(type default)
		)
	)
	(wire
		(pts
			(xy 284.48 151.13) (xy 288.29 151.13)
		)
		(stroke
			(width 0)
			(type default)
		)
	)
	(wire
		(pts
			(xy 109.22 153.67) (xy 109.22 154.94)
		)
		(stroke
			(width 0)
			(type default)
		)
	)
	(wire
		(pts
			(xy 109.22 142.24) (xy 109.22 144.78)
		)
		(stroke
			(width 0)
			(type default)
		)
	)
	(wire
		(pts
			(xy 95.885 56.515) (xy 95.885 57.785)
		)
		(stroke
			(width 0)
			(type default)
		)
	)
	(wire
		(pts
			(xy 177.8 85.09) (xy 175.26 85.09)
		)
		(stroke
			(width 0)
			(type default)
		)
	)
	(wire
		(pts
			(xy 190.5 77.47) (xy 190.5 75.565)
		)
		(stroke
			(width 0)
			(type default)
		)
	)
	(wire
		(pts
			(xy 215.265 75.565) (xy 243.84 75.565)
		)
		(stroke
			(width 0)
			(type default)
		)
	)
	(wire
		(pts
			(xy 243.84 75.565) (xy 252.73 75.565)
		)
		(stroke
			(width 0)
			(type default)
		)
	)
	(wire
		(pts
			(xy 312.42 114.3) (xy 316.23 114.3)
		)
		(stroke
			(width 0)
			(type default)
		)
	)
	(wire
		(pts
			(xy 231.775 53.975) (xy 231.775 56.515)
		)
		(stroke
			(width 0)
			(type default)
		)
	)
	(wire
		(pts
			(xy 118.745 115.57) (xy 130.81 115.57)
		)
		(stroke
			(width 0)
			(type default)
		)
	)
	(wire
		(pts
			(xy 177.165 135.89) (xy 177.165 134.62)
		)
		(stroke
			(width 0)
			(type default)
		)
	)
	(wire
		(pts
			(xy 74.295 48.895) (xy 79.375 48.895)
		)
		(stroke
			(width 0)
			(type default)
		)
	)
	(wire
		(pts
			(xy 61.595 222.25) (xy 100.965 222.25)
		)
		(stroke
			(width 0)
			(type default)
		)
	)
	(wire
		(pts
			(xy 190.5 83.82) (xy 190.5 82.55)
		)
		(stroke
			(width 0)
			(type default)
		)
	)
	(wire
		(pts
			(xy 61.595 227.965) (xy 100.965 227.965)
		)
		(stroke
			(width 0)
			(type default)
		)
	)
	(wire
		(pts
			(xy 198.755 98.425) (xy 198.755 99.695)
		)
		(stroke
			(width 0)
			(type default)
		)
	)
	(wire
		(pts
			(xy 118.745 110.49) (xy 130.81 110.49)
		)
		(stroke
			(width 0)
			(type default)
		)
	)
	(wire
		(pts
			(xy 130.81 95.25) (xy 118.745 95.25)
		)
		(stroke
			(width 0)
			(type default)
		)
	)
	(wire
		(pts
			(xy 118.745 121.92) (xy 130.81 121.92)
		)
		(stroke
			(width 0)
			(type default)
		)
	)
	(wire
		(pts
			(xy 177.165 140.97) (xy 177.165 142.24)
		)
		(stroke
			(width 0)
			(type default)
		)
	)
	(wire
		(pts
			(xy 207.01 91.44) (xy 244.475 91.44)
		)
		(stroke
			(width 0)
			(type default)
		)
	)
	(wire
		(pts
			(xy 115.57 162.56) (xy 109.22 162.56)
		)
		(stroke
			(width 0)
			(type default)
		)
	)
	(wire
		(pts
			(xy 61.595 213.995) (xy 100.965 213.995)
		)
		(stroke
			(width 0)
			(type default)
		)
	)
	(wire
		(pts
			(xy 121.92 160.02) (xy 121.92 162.56)
		)
		(stroke
			(width 0)
			(type default)
		)
	)
	(wire
		(pts
			(xy 56.515 217.17) (xy 45.085 217.17)
		)
		(stroke
			(width 0)
			(type default)
		)
	)
	(wire
		(pts
			(xy 198.755 91.44) (xy 207.01 91.44)
		)
		(stroke
			(width 0)
			(type default)
		)
	)
	(wire
		(pts
			(xy 92.075 92.71) (xy 86.36 92.71)
		)
		(stroke
			(width 0)
			(type default)
		)
	)
	(wire
		(pts
			(xy 45.085 219.71) (xy 45.085 222.25)
		)
		(stroke
			(width 0)
			(type default)
		)
	)
	(wire
		(pts
			(xy 207.01 75.565) (xy 215.265 75.565)
		)
		(stroke
			(width 0)
			(type default)
		)
	)
	(wire
		(pts
			(xy 120.65 88.9) (xy 120.65 69.85)
		)
		(stroke
			(width 0)
			(type default)
		)
	)
	(wire
		(pts
			(xy 112.395 77.47) (xy 112.395 78.74)
		)
		(stroke
			(width 0)
			(type default)
		)
	)
	(wire
		(pts
			(xy 284.48 142.24) (xy 288.29 142.24)
		)
		(stroke
			(width 0)
			(type default)
		)
	)
	(wire
		(pts
			(xy 115.57 162.56) (xy 115.57 163.83)
		)
		(stroke
			(width 0)
			(type default)
		)
	)
	(wire
		(pts
			(xy 79.375 56.515) (xy 79.375 57.785)
		)
		(stroke
			(width 0)
			(type default)
		)
	)
	(bus
		(pts
			(xy 115.57 88.265) (xy 116.205 88.9)
		)
		(stroke
			(width 0)
			(type default)
		)
	)
	(wire
		(pts
			(xy 285.75 135.89) (xy 289.56 135.89)
		)
		(stroke
			(width 0)
			(type default)
		)
	)
	(wire
		(pts
			(xy 118.745 105.41) (xy 130.81 105.41)
		)
		(stroke
			(width 0)
			(type default)
		)
	)
	(wire
		(pts
			(xy 109.22 144.78) (xy 109.22 153.67)
		)
		(stroke
			(width 0)
			(type default)
		)
	)
	(bus
		(pts
			(xy 116.205 124.46) (xy 116.205 127)
		)
		(stroke
			(width 0)
			(type default)
		)
	)
	(wire
		(pts
			(xy 118.11 144.78) (xy 121.92 144.78)
		)
		(stroke
			(width 0)
			(type default)
		)
	)
	(wire
		(pts
			(xy 207.01 53.975) (xy 198.755 53.975)
		)
		(stroke
			(width 0)
			(type default)
		)
	)
	(bus
		(pts
			(xy 116.205 110.49) (xy 116.205 113.03)
		)
		(stroke
			(width 0)
			(type default)
		)
	)
	(wire
		(pts
			(xy 288.29 142.24) (xy 288.29 144.78)
		)
		(stroke
			(width 0)
			(type default)
		)
	)
	(bus
		(pts
			(xy 116.205 102.87) (xy 116.205 105.41)
		)
		(stroke
			(width 0)
			(type default)
		)
	)
	(wire
		(pts
			(xy 223.52 53.975) (xy 215.265 53.975)
		)
		(stroke
			(width 0)
			(type default)
		)
	)
	(wire
		(pts
			(xy 257.81 75.565) (xy 260.985 75.565)
		)
		(stroke
			(width 0)
			(type default)
		)
	)
	(wire
		(pts
			(xy 175.26 144.78) (xy 177.165 144.78)
		)
		(stroke
			(width 0)
			(type default)
		)
	)
	(wire
		(pts
			(xy 256.54 61.595) (xy 256.54 62.865)
		)
		(stroke
			(width 0)
			(type default)
		)
	)
	(wire
		(pts
			(xy 118.745 99.06) (xy 130.81 99.06)
		)
		(stroke
			(width 0)
			(type default)
		)
	)
	(bus
		(pts
			(xy 116.205 127) (xy 116.205 129.54)
		)
		(stroke
			(width 0)
			(type default)
		)
	)
	(wire
		(pts
			(xy 45.085 222.25) (xy 45.085 225.425)
		)
		(stroke
			(width 0)
			(type default)
		)
	)
	(wire
		(pts
			(xy 104.14 48.895) (xy 95.885 48.895)
		)
		(stroke
			(width 0)
			(type default)
		)
	)
	(wire
		(pts
			(xy 116.84 213.995) (xy 116.84 217.17)
		)
		(stroke
			(width 0)
			(type default)
		)
	)
	(wire
		(pts
			(xy 177.165 134.62) (xy 175.26 134.62)
		)
		(stroke
			(width 0)
			(type default)
		)
	)
	(wire
		(pts
			(xy 128.905 48.895) (xy 128.905 85.09)
		)
		(stroke
			(width 0)
			(type default)
		)
	)
	(wire
		(pts
			(xy 280.67 116.84) (xy 289.56 116.84)
		)
		(stroke
			(width 0)
			(type default)
		)
	)
	(wire
		(pts
			(xy 112.395 48.895) (xy 112.395 51.435)
		)
		(stroke
			(width 0)
			(type default)
		)
	)
	(wire
		(pts
			(xy 260.985 53.975) (xy 260.985 75.565)
		)
		(stroke
			(width 0)
			(type default)
		)
	)
	(wire
		(pts
			(xy 112.395 69.85) (xy 112.395 72.39)
		)
		(stroke
			(width 0)
			(type default)
		)
	)
	(wire
		(pts
			(xy 104.14 69.85) (xy 104.14 72.39)
		)
		(stroke
			(width 0)
			(type default)
		)
	)
	(wire
		(pts
			(xy 273.05 135.89) (xy 273.05 138.43)
		)
		(stroke
			(width 0)
			(type default)
		)
	)
	(wire
		(pts
			(xy 280.67 124.46) (xy 289.56 124.46)
		)
		(stroke
			(width 0)
			(type default)
		)
	)
	(wire
		(pts
			(xy 106.045 217.17) (xy 116.84 217.17)
		)
		(stroke
			(width 0)
			(type default)
		)
	)
	(wire
		(pts
			(xy 177.165 142.24) (xy 175.26 142.24)
		)
		(stroke
			(width 0)
			(type default)
		)
	)
	(wire
		(pts
			(xy 215.265 53.975) (xy 207.01 53.975)
		)
		(stroke
			(width 0)
			(type default)
		)
	)
	(wire
		(pts
			(xy 116.84 217.17) (xy 116.84 219.71)
		)
		(stroke
			(width 0)
			(type default)
		)
	)
	(bus
		(pts
			(xy 116.205 129.54) (xy 116.205 132.08)
		)
		(stroke
			(width 0)
			(type default)
		)
	)
	(wire
		(pts
			(xy 207.01 93.345) (xy 207.01 91.44)
		)
		(stroke
			(width 0)
			(type default)
		)
	)
	(wire
		(pts
			(xy 312.42 116.84) (xy 339.09 116.84)
		)
		(stroke
			(width 0)
			(type default)
		)
	)
	(wire
		(pts
			(xy 231.775 53.975) (xy 223.52 53.975)
		)
		(stroke
			(width 0)
			(type default)
		)
	)
	(wire
		(pts
			(xy 130.81 134.62) (xy 118.745 134.62)
		)
		(stroke
			(width 0)
			(type default)
		)
	)
	(wire
		(pts
			(xy 240.03 53.975) (xy 240.03 56.515)
		)
		(stroke
			(width 0)
			(type default)
		)
	)
	(wire
		(pts
			(xy 280.67 127) (xy 289.56 127)
		)
		(stroke
			(width 0)
			(type default)
		)
	)
	(wire
		(pts
			(xy 95.885 48.895) (xy 87.63 48.895)
		)
		(stroke
			(width 0)
			(type default)
		)
	)
	(wire
		(pts
			(xy 56.515 213.995) (xy 45.085 213.995)
		)
		(stroke
			(width 0)
			(type default)
		)
	)
	(wire
		(pts
			(xy 183.515 105.41) (xy 175.26 105.41)
		)
		(stroke
			(width 0)
			(type default)
		)
	)
	(wire
		(pts
			(xy 280.67 132.08) (xy 289.56 132.08)
		)
		(stroke
			(width 0)
			(type default)
		)
	)
	(wire
		(pts
			(xy 321.31 114.3) (xy 327.66 114.3)
		)
		(stroke
			(width 0)
			(type default)
		)
	)
	(wire
		(pts
			(xy 177.8 53.975) (xy 190.5 53.975)
		)
		(stroke
			(width 0)
			(type default)
		)
	)
	(wire
		(pts
			(xy 240.03 53.975) (xy 248.285 53.975)
		)
		(stroke
			(width 0)
			(type default)
		)
	)
	(wire
		(pts
			(xy 106.045 225.425) (xy 116.84 225.425)
		)
		(stroke
			(width 0)
			(type default)
		)
	)
	(wire
		(pts
			(xy 109.22 160.02) (xy 109.22 162.56)
		)
		(stroke
			(width 0)
			(type default)
		)
	)
	(wire
		(pts
			(xy 327.66 113.03) (xy 327.66 114.3)
		)
		(stroke
			(width 0)
			(type default)
		)
	)
	(wire
		(pts
			(xy 106.045 227.965) (xy 116.84 227.965)
		)
		(stroke
			(width 0)
			(type default)
		)
	)
	(bus
		(pts
			(xy 116.205 113.03) (xy 116.205 115.57)
		)
		(stroke
			(width 0)
			(type default)
		)
	)
	(wire
		(pts
			(xy 95.885 69.85) (xy 95.885 72.39)
		)
		(stroke
			(width 0)
			(type default)
		)
	)
	(wire
		(pts
			(xy 112.395 56.515) (xy 112.395 57.785)
		)
		(stroke
			(width 0)
			(type default)
		)
	)
	(wire
		(pts
			(xy 86.36 92.71) (xy 86.36 101.6)
		)
		(stroke
			(width 0)
			(type default)
		)
	)
	(wire
		(pts
			(xy 190.5 75.565) (xy 198.755 75.565)
		)
		(stroke
			(width 0)
			(type default)
		)
	)
	(wire
		(pts
			(xy 45.085 208.915) (xy 45.085 211.455)
		)
		(stroke
			(width 0)
			(type default)
		)
	)
	(wire
		(pts
			(xy 273.05 135.89) (xy 280.67 135.89)
		)
		(stroke
			(width 0)
			(type default)
		)
	)
	(wire
		(pts
			(xy 190.5 91.44) (xy 198.755 91.44)
		)
		(stroke
			(width 0)
			(type default)
		)
	)
	(wire
		(pts
			(xy 260.985 91.44) (xy 260.985 75.565)
		)
		(stroke
			(width 0)
			(type default)
		)
	)
	(wire
		(pts
			(xy 130.81 113.03) (xy 118.745 113.03)
		)
		(stroke
			(width 0)
			(type default)
		)
	)
	(wire
		(pts
			(xy 116.84 227.965) (xy 116.84 229.235)
		)
		(stroke
			(width 0)
			(type default)
		)
	)
	(wire
		(pts
			(xy 248.285 53.975) (xy 248.285 56.515)
		)
		(stroke
			(width 0)
			(type default)
		)
	)
	(bus
		(pts
			(xy 116.205 119.38) (xy 116.205 121.92)
		)
		(stroke
			(width 0)
			(type default)
		)
	)
	(wire
		(pts
			(xy 45.085 206.375) (xy 45.085 208.915)
		)
		(stroke
			(width 0)
			(type default)
		)
	)
	(wire
		(pts
			(xy 231.775 53.975) (xy 240.03 53.975)
		)
		(stroke
			(width 0)
			(type default)
		)
	)
	(wire
		(pts
			(xy 106.045 222.25) (xy 116.84 222.25)
		)
		(stroke
			(width 0)
			(type default)
		)
	)
	(wire
		(pts
			(xy 183.515 99.06) (xy 175.26 99.06)
		)
		(stroke
			(width 0)
			(type default)
		)
	)
	(wire
		(pts
			(xy 116.84 206.375) (xy 116.84 208.915)
		)
		(stroke
			(width 0)
			(type default)
		)
	)
	(wire
		(pts
			(xy 104.14 48.895) (xy 104.14 51.435)
		)
		(stroke
			(width 0)
			(type default)
		)
	)
	(wire
		(pts
			(xy 87.63 56.515) (xy 87.63 57.785)
		)
		(stroke
			(width 0)
			(type default)
		)
	)
	(wire
		(pts
			(xy 198.755 61.595) (xy 198.755 62.865)
		)
		(stroke
			(width 0)
			(type default)
		)
	)
	(wire
		(pts
			(xy 183.515 107.95) (xy 175.26 107.95)
		)
		(stroke
			(width 0)
			(type default)
		)
	)
	(wire
		(pts
			(xy 45.085 213.995) (xy 45.085 217.17)
		)
		(stroke
			(width 0)
			(type default)
		)
	)
	(wire
		(pts
			(xy 175.26 127) (xy 184.785 127)
		)
		(stroke
			(width 0)
			(type default)
		)
	)
	(wire
		(pts
			(xy 231.775 61.595) (xy 231.775 62.865)
		)
		(stroke
			(width 0)
			(type default)
		)
	)
	(label "ETH3_P"
		(at 183.515 111.76 180)
		(effects
			(font
				(size 1.27 1.27)
			)
			(justify right bottom)
		)
	)
	(label "ETH4_P"
		(at 280.67 129.54 0)
		(effects
			(font
				(size 1.27 1.27)
			)
			(justify left bottom)
		)
	)
	(label "LED_LINK"
		(at 81.28 222.25 180)
		(effects
			(font
				(size 1.27 1.27)
			)
			(justify right bottom)
		)
	)
	(label "ETH2_P"
		(at 280.67 119.38 0)
		(effects
			(font
				(size 1.27 1.27)
			)
			(justify left bottom)
		)
	)
	(label "ETH.TXD0"
		(at 118.745 107.95 0)
		(effects
			(font
				(size 1.27 1.27)
			)
			(justify left bottom)
		)
	)
	(label "ETH.RXC"
		(at 81.28 217.17 180)
		(effects
			(font
				(size 1.27 1.27)
			)
			(justify right bottom)
		)
	)
	(label "ETH.~{RESET}"
		(at 118.745 92.71 0)
		(effects
			(font
				(size 1.27 1.27)
			)
			(justify left bottom)
		)
	)
	(label "ETH3_N"
		(at 280.67 127 0)
		(effects
			(font
				(size 1.27 1.27)
			)
			(justify left bottom)
		)
	)
	(label "AVDDH"
		(at 129.54 88.9 180)
		(effects
			(font
				(size 1.27 1.27)
			)
			(justify right bottom)
		)
	)
	(label "ETH3_N"
		(at 183.515 114.3 180)
		(effects
			(font
				(size 1.27 1.27)
			)
			(justify right bottom)
		)
	)
	(label "ETH.RXD1"
		(at 81.28 211.455 180)
		(effects
			(font
				(size 1.27 1.27)
			)
			(justify right bottom)
		)
	)
	(label "ETH4_N"
		(at 183.515 120.65 180)
		(effects
			(font
				(size 1.27 1.27)
			)
			(justify right bottom)
		)
	)
	(label "ETH1_P"
		(at 280.67 114.3 0)
		(effects
			(font
				(size 1.27 1.27)
			)
			(justify left bottom)
		)
	)
	(label "ETH1_P"
		(at 183.515 99.06 180)
		(effects
			(font
				(size 1.27 1.27)
			)
			(justify right bottom)
		)
	)
	(label "ETH2_P"
		(at 183.515 105.41 180)
		(effects
			(font
				(size 1.27 1.27)
			)
			(justify right bottom)
		)
	)
	(label "ETH3_P"
		(at 280.67 124.46 0)
		(effects
			(font
				(size 1.27 1.27)
			)
			(justify left bottom)
		)
	)
	(label "LED_LINK"
		(at 339.09 116.84 180)
		(effects
			(font
				(size 1.27 1.27)
			)
			(justify right bottom)
		)
	)
	(label "ETH.RX_CTL"
		(at 118.745 121.92 0)
		(effects
			(font
				(size 1.27 1.27)
			)
			(justify left bottom)
		)
	)
	(label "ETH1_N"
		(at 280.67 116.84 0)
		(effects
			(font
				(size 1.27 1.27)
			)
			(justify left bottom)
		)
	)
	(label "ETH.RXC"
		(at 118.745 134.62 0)
		(effects
			(font
				(size 1.27 1.27)
			)
			(justify left bottom)
		)
	)
	(label "ETH2_N"
		(at 183.515 107.95 180)
		(effects
			(font
				(size 1.27 1.27)
			)
			(justify right bottom)
		)
	)
	(label "ETH1_N"
		(at 183.515 101.6 180)
		(effects
			(font
				(size 1.27 1.27)
			)
			(justify right bottom)
		)
	)
	(label "ETH4_N"
		(at 280.67 132.08 0)
		(effects
			(font
				(size 1.27 1.27)
			)
			(justify left bottom)
		)
	)
	(label "ETH.TXC"
		(at 118.745 118.11 0)
		(effects
			(font
				(size 1.27 1.27)
			)
			(justify left bottom)
		)
	)
	(label "ETH.MDIO"
		(at 113.665 101.6 180)
		(effects
			(font
				(size 1.27 1.27)
			)
			(justify right bottom)
		)
	)
	(label "LED_SPD"
		(at 330.2 142.24 180)
		(effects
			(font
				(size 1.27 1.27)
			)
			(justify right bottom)
		)
	)
	(label "ETH.TXD1"
		(at 118.745 110.49 0)
		(effects
			(font
				(size 1.27 1.27)
			)
			(justify left bottom)
		)
	)
	(label "ETH.MDIO"
		(at 118.745 101.6 0)
		(effects
			(font
				(size 1.27 1.27)
			)
			(justify left bottom)
		)
	)
	(label "ETH.RXD2"
		(at 81.28 208.915 180)
		(effects
			(font
				(size 1.27 1.27)
			)
			(justify right bottom)
		)
	)
	(label "ETH.TXD2"
		(at 118.745 113.03 0)
		(effects
			(font
				(size 1.27 1.27)
			)
			(justify left bottom)
		)
	)
	(label "AVDDL"
		(at 182.245 88.9 180)
		(effects
			(font
				(size 1.27 1.27)
			)
			(justify right bottom)
		)
	)
	(label "ETH.RXD3"
		(at 118.745 132.08 0)
		(effects
			(font
				(size 1.27 1.27)
			)
			(justify left bottom)
		)
	)
	(label "ETH.MDC"
		(at 118.745 99.06 0)
		(effects
			(font
				(size 1.27 1.27)
			)
			(justify left bottom)
		)
	)
	(label "ETH.RXD0"
		(at 81.28 213.995 180)
		(effects
			(font
				(size 1.27 1.27)
			)
			(justify right bottom)
		)
	)
	(label "ETH.TXD3"
		(at 118.745 115.57 0)
		(effects
			(font
				(size 1.27 1.27)
			)
			(justify left bottom)
		)
	)
	(label "LED_SPD"
		(at 184.785 129.54 180)
		(effects
			(font
				(size 1.27 1.27)
			)
			(justify right bottom)
		)
	)
	(label "ETH2_N"
		(at 280.67 121.92 0)
		(effects
			(font
				(size 1.27 1.27)
			)
			(justify left bottom)
		)
	)
	(label "ETH.TX_CTL"
		(at 118.745 105.41 0)
		(effects
			(font
				(size 1.27 1.27)
			)
			(justify left bottom)
		)
	)
	(label "AVDDL_PLL"
		(at 186.055 91.44 180)
		(effects
			(font
				(size 1.27 1.27)
			)
			(justify right bottom)
		)
	)
	(label "ETH.RXD3"
		(at 81.28 206.375 180)
		(effects
			(font
				(size 1.27 1.27)
			)
			(justify right bottom)
		)
	)
	(label "ETH.RXD2"
		(at 118.745 129.54 0)
		(effects
			(font
				(size 1.27 1.27)
			)
			(justify left bottom)
		)
	)
	(label "ETH.RXD1"
		(at 118.745 127 0)
		(effects
			(font
				(size 1.27 1.27)
			)
			(justify left bottom)
		)
	)
	(label "ETH.RXD0"
		(at 118.745 124.46 0)
		(effects
			(font
				(size 1.27 1.27)
			)
			(justify left bottom)
		)
	)
	(label "ETH.REF_CLK"
		(at 118.745 138.43 0)
		(effects
			(font
				(size 1.27 1.27)
			)
			(justify left bottom)
		)
	)
	(label "ETH.~{RESET}"
		(at 113.665 92.71 180)
		(effects
			(font
				(size 1.27 1.27)
			)
			(justify right bottom)
		)
	)
	(label "ETH4_P"
		(at 183.515 118.11 180)
		(effects
			(font
				(size 1.27 1.27)
			)
			(justify right bottom)
		)
	)
	(label "ETH.~{INT}"
		(at 118.745 95.25 0)
		(effects
			(font
				(size 1.27 1.27)
			)
			(justify left bottom)
		)
	)
	(label "ETH.REF_CLK"
		(at 81.28 227.965 180)
		(effects
			(font
				(size 1.27 1.27)
			)
			(justify right bottom)
		)
	)
	(label "LED_LINK"
		(at 184.785 127 180)
		(effects
			(font
				(size 1.27 1.27)
			)
			(justify right bottom)
		)
	)
	(label "LED_SPD"
		(at 81.28 219.71 180)
		(effects
			(font
				(size 1.27 1.27)
			)
			(justify right bottom)
		)
	)
	(label "ETH.RX_CTL"
		(at 81.28 225.425 180)
		(effects
			(font
				(size 1.27 1.27)
			)
			(justify right bottom)
		)
	)
	(hierarchical_label "ETH{RGMII}"
		(shape bidirectional)
		(at 113.665 88.265 180)
		(effects
			(font
				(size 1.27 1.27)
			)
			(justify right)
		)
	)
	(symbol
		(lib_id "antmicroInterfaceControllers:KSZ9031RNXCA")
		(at 130.81 85.09 0)
		(unit 1)
		(exclude_from_sim no)
		(in_bom yes)
		(on_board yes)
		(dnp no)
		(fields_autoplaced yes)
		(property "Reference" "U15"
			(at 153.035 77.47 0)
			(effects
				(font
					(size 1.27 1.27)
				)
			)
		)
		(property "Value" "KSZ9031RNXCA"
			(at 153.035 80.01 0)
			(effects
				(font
					(size 1.27 1.27)
					(thickness 0.15)
				)
			)
		)
		(property "Footprint" "antmicro-footprints:QFN-48-1EP_7x7x0.9mm_P0.5mm_EP3.5x3.5mm"
			(at 207.01 95.25 0)
			(effects
				(font
					(size 1.27 1.27)
					(thickness 0.15)
				)
				(justify left bottom)
				(hide yes)
			)
		)
		(property "Datasheet" "http://ww1.microchip.com/downloads/en/DeviceDoc/00002117F.pdf"
			(at 207.01 97.79 0)
			(effects
				(font
					(size 1.27 1.27)
					(thickness 0.15)
				)
				(justify left bottom)
				(hide yes)
			)
		)
		(property "Description" ""
			(at 130.81 85.09 0)
			(effects
				(font
					(size 1.27 1.27)
				)
			)
		)
		(property "Manufacturer" "Microchip Technology"
			(at 207.01 100.33 0)
			(effects
				(font
					(size 1.27 1.27)
					(thickness 0.15)
				)
				(justify left bottom)
				(hide yes)
			)
		)
		(property "MPN" "KSZ9031RNXCA"
			(at 207.01 102.87 0)
			(effects
				(font
					(size 1.27 1.27)
					(thickness 0.15)
				)
				(justify left bottom)
				(hide yes)
			)
		)
		(property "Author" "Antmicro"
			(at 207.01 105.41 0)
			(effects
				(font
					(size 1.27 1.27)
					(thickness 0.15)
				)
				(justify left bottom)
				(hide yes)
			)
		)
		(property "License" "Apache-2.0"
			(at 207.01 107.95 0)
			(effects
				(font
					(size 1.27 1.27)
					(thickness 0.15)
				)
				(justify left bottom)
				(hide yes)
			)
		)
		(pin "1"
		)
		(pin "10"
		)
		(pin "11"
		)
		(pin "12"
		)
		(pin "13"
		)
		(pin "14"
		)
		(pin "15"
		)
		(pin "16"
		)
		(pin "17"
		)
		(pin "18"
		)
		(pin "19"
		)
		(pin "2"
		)
		(pin "20"
		)
		(pin "21"
		)
		(pin "22"
		)
		(pin "23"
		)
		(pin "24"
		)
		(pin "25"
		)
		(pin "26"
		)
		(pin "27"
		)
		(pin "28"
		)
		(pin "29"
		)
		(pin "3"
		)
		(pin "30"
		)
		(pin "31"
		)
		(pin "32"
		)
		(pin "33"
		)
		(pin "34"
		)
		(pin "35"
		)
		(pin "36"
		)
		(pin "37"
		)
		(pin "38"
		)
		(pin "39"
		)
		(pin "4"
		)
		(pin "40"
		)
		(pin "41"
		)
		(pin "42"
		)
		(pin "43"
		)
		(pin "44"
		)
		(pin "45"
		)
		(pin "46"
		)
		(pin "47"
		)
		(pin "48"
		)
		(pin "49"
		)
		(pin "5"
		)
		(pin "6"
		)
		(pin "7"
		)
		(pin "8"
		)
		(pin "9"
		)
		(instances
			(project "sodimm-ddr5-tester"
				(path ""
					(reference "U15")
					(unit 1)
				)
			)
		)
	)
	(symbol
		(lib_id "antmicroResistors0402:R_12k1_0402")
		(at 177.165 140.97 90)
		(unit 1)
		(exclude_from_sim no)
		(in_bom yes)
		(on_board yes)
		(dnp no)
		(fields_autoplaced yes)
		(property "Reference" "R112"
			(at 179.705 137.16 90)
			(effects
				(font
					(size 1.27 1.27)
				)
				(justify right)
			)
		)
		(property "Value" "R_12k1_0402"
			(at 189.865 120.65 0)
			(effects
				(font
					(size 1.27 1.27)
					(thickness 0.15)
				)
				(justify left bottom)
				(hide yes)
			)
		)
		(property "Footprint" "antmicro-footprints:R_0402_1005Metric"
			(at 192.405 120.65 0)
			(effects
				(font
					(size 1.27 1.27)
					(thickness 0.15)
				)
				(justify left bottom)
				(hide yes)
			)
		)
		(property "Datasheet" "https://www.bourns.com/docs/product-datasheets/cr.pdf"
			(at 194.945 120.65 0)
			(effects
				(font
					(size 1.27 1.27)
					(thickness 0.15)
				)
				(justify left bottom)
				(hide yes)
			)
		)
		(property "Description" ""
			(at 177.165 140.97 0)
			(effects
				(font
					(size 1.27 1.27)
				)
			)
		)
		(property "Manufacturer" "Bourns"
			(at 200.025 120.65 0)
			(effects
				(font
					(size 1.27 1.27)
					(thickness 0.15)
				)
				(justify left bottom)
				(hide yes)
			)
		)
		(property "MPN" "CR0402-FX-1212GLF"
			(at 197.485 120.65 0)
			(effects
				(font
					(size 1.27 1.27)
					(thickness 0.15)
				)
				(justify left bottom)
				(hide yes)
			)
		)
		(property "Val" "12k1"
			(at 179.705 140.3349 90)
			(effects
				(font
					(size 1.27 1.27)
					(thickness 0.15)
				)
				(justify right)
			)
		)
		(property "License" "Apache-2.0"
			(at 202.565 120.65 0)
			(effects
				(font
					(size 1.27 1.27)
					(thickness 0.15)
				)
				(justify left bottom)
				(hide yes)
			)
		)
		(property "Author" "Antmicro"
			(at 205.105 120.65 0)
			(effects
				(font
					(size 1.27 1.27)
					(thickness 0.15)
				)
				(justify left bottom)
				(hide yes)
			)
		)
		(property "Tolerance" "1%"
			(at 187.325 120.65 0)
			(effects
				(font
					(size 1.27 1.27)
				)
				(justify left bottom)
				(hide yes)
			)
		)
		(pin "1"
		)
		(pin "2"
		)
		(instances
			(project "sodimm-ddr5-tester"
				(path ""
					(reference "R112")
					(unit 1)
				)
			)
		)
	)
	(symbol
		(lib_id "antmicropower:GND")
		(at 177.165 146.685 0)
		(unit 1)
		(exclude_from_sim no)
		(in_bom yes)
		(on_board yes)
		(dnp no)
		(fields_autoplaced yes)
		(property "Reference" "#PWR0259"
			(at 177.165 153.035 0)
			(effects
				(font
					(size 1.27 1.27)
				)
				(hide yes)
			)
		)
		(property "Value" "GND"
			(at 179.07 147.955 0)
			(effects
				(font
					(size 1.27 1.27)
					(thickness 0.15)
				)
				(justify left)
			)
		)
		(property "Footprint" ""
			(at 186.055 154.305 0)
			(effects
				(font
					(size 1.27 1.27)
					(thickness 0.15)
				)
				(justify left bottom)
				(hide yes)
			)
		)
		(property "Datasheet" ""
			(at 186.055 159.385 0)
			(effects
				(font
					(size 1.27 1.27)
					(thickness 0.15)
				)
				(justify left bottom)
				(hide yes)
			)
		)
		(property "Description" ""
			(at 186.055 161.925 0)
			(effects
				(font
					(size 1.27 1.27)
				)
				(justify left bottom)
				(hide yes)
			)
		)
		(property "Author" "Antmicro"
			(at 186.055 154.305 0)
			(effects
				(font
					(size 1.27 1.27)
					(thickness 0.15)
				)
				(justify left bottom)
				(hide yes)
			)
		)
		(property "License" "Apache-2.0"
			(at 186.055 156.845 0)
			(effects
				(font
					(size 1.27 1.27)
					(thickness 0.15)
				)
				(justify left bottom)
				(hide yes)
			)
		)
		(pin "1"
		)
		(instances
			(project "sodimm-ddr5-tester"
				(path ""
					(reference "#PWR0259")
					(unit 1)
				)
			)
		)
	)
	(symbol
		(lib_id "antmicropower:GND")
		(at 115.57 163.83 0)
		(mirror y)
		(unit 1)
		(exclude_from_sim no)
		(in_bom yes)
		(on_board yes)
		(dnp no)
		(property "Reference" "#PWR0256"
			(at 115.57 170.18 0)
			(effects
				(font
					(size 1.27 1.27)
				)
				(hide yes)
			)
		)
		(property "Value" "GND"
			(at 113.538 167.64 0)
			(effects
				(font
					(size 1.27 1.27)
					(thickness 0.15)
				)
				(justify right)
			)
		)
		(property "Footprint" ""
			(at 106.68 171.45 0)
			(effects
				(font
					(size 1.27 1.27)
					(thickness 0.15)
				)
				(justify left bottom)
				(hide yes)
			)
		)
		(property "Datasheet" ""
			(at 106.68 176.53 0)
			(effects
				(font
					(size 1.27 1.27)
					(thickness 0.15)
				)
				(justify left bottom)
				(hide yes)
			)
		)
		(property "Description" ""
			(at 106.68 179.07 0)
			(effects
				(font
					(size 1.27 1.27)
				)
				(justify left bottom)
				(hide yes)
			)
		)
		(property "Author" "Antmicro"
			(at 106.68 171.45 0)
			(effects
				(font
					(size 1.27 1.27)
					(thickness 0.15)
				)
				(justify left bottom)
				(hide yes)
			)
		)
		(property "License" "Apache-2.0"
			(at 106.68 173.99 0)
			(effects
				(font
					(size 1.27 1.27)
					(thickness 0.15)
				)
				(justify left bottom)
				(hide yes)
			)
		)
		(pin "1"
		)
		(instances
			(project "sodimm-ddr5-tester"
				(path ""
					(reference "#PWR0256")
					(unit 1)
				)
			)
		)
	)
	(symbol
		(lib_id "antmicroCapacitors0402:C_4u7_0402")
		(at 215.265 77.47 90)
		(mirror x)
		(unit 1)
		(exclude_from_sim no)
		(in_bom yes)
		(on_board yes)
		(dnp no)
		(property "Reference" "C146"
			(at 215.9 78.105 90)
			(effects
				(font
					(size 1.27 1.27)
				)
				(justify right)
			)
		)
		(property "Value" "C_4u7_0402"
			(at 225.425 97.79 0)
			(effects
				(font
					(size 1.27 1.27)
					(thickness 0.15)
				)
				(justify left bottom)
				(hide yes)
			)
		)
		(property "Footprint" "antmicro-footprints:C_0402_1005Metric"
			(at 227.965 97.79 0)
			(effects
				(font
					(size 1.27 1.27)
					(thickness 0.15)
				)
				(justify left bottom)
				(hide yes)
			)
		)
		(property "Datasheet" "https://www.murata.com/products/productdetail?partno=GRM155R61A475MEAA%23"
			(at 230.505 97.79 0)
			(effects
				(font
					(size 1.27 1.27)
					(thickness 0.15)
				)
				(justify left bottom)
				(hide yes)
			)
		)
		(property "Description" ""
			(at 215.265 77.47 0)
			(effects
				(font
					(size 1.27 1.27)
				)
			)
		)
		(property "Manufacturer" "Murata"
			(at 235.585 97.79 0)
			(effects
				(font
					(size 1.27 1.27)
					(thickness 0.15)
				)
				(justify left bottom)
				(hide yes)
			)
		)
		(property "MPN" "GRM155R61A475MEAAD"
			(at 233.045 97.79 0)
			(effects
				(font
					(size 1.27 1.27)
					(thickness 0.15)
				)
				(justify left bottom)
				(hide yes)
			)
		)
		(property "Val" "4u7"
			(at 215.9 81.915 90)
			(effects
				(font
					(size 1.27 1.27)
					(thickness 0.15)
				)
				(justify right)
			)
		)
		(property "License" "Apache-2.0"
			(at 238.125 97.79 0)
			(effects
				(font
					(size 1.27 1.27)
					(thickness 0.15)
				)
				(justify left bottom)
				(hide yes)
			)
		)
		(property "Author" "Antmicro"
			(at 240.665 97.79 0)
			(effects
				(font
					(size 1.27 1.27)
					(thickness 0.15)
				)
				(justify left bottom)
				(hide yes)
			)
		)
		(property "Voltage" ""
			(at 243.205 97.79 0)
			(effects
				(font
					(size 1.27 1.27)
				)
				(justify left bottom)
				(hide yes)
			)
		)
		(property "Dielectric" ""
			(at 245.745 97.79 0)
			(effects
				(font
					(size 1.27 1.27)
				)
				(justify left bottom)
				(hide yes)
			)
		)
		(pin "1"
		)
		(pin "2"
		)
		(instances
			(project "sodimm-ddr5-tester"
				(path ""
					(reference "C146")
					(unit 1)
				)
			)
		)
	)
	(symbol
		(lib_id "antmicroCapacitors0402:C_470n_0402")
		(at 207.01 77.47 90)
		(mirror x)
		(unit 1)
		(exclude_from_sim no)
		(in_bom yes)
		(on_board yes)
		(dnp no)
		(property "Reference" "C143"
			(at 207.645 78.105 90)
			(effects
				(font
					(size 1.27 1.27)
				)
				(justify right)
			)
		)
		(property "Value" "C_470n_0402"
			(at 217.17 97.79 0)
			(effects
				(font
					(size 1.27 1.27)
					(thickness 0.15)
				)
				(justify left bottom)
				(hide yes)
			)
		)
		(property "Footprint" "antmicro-footprints:C_0402_1005Metric"
			(at 219.71 97.79 0)
			(effects
				(font
					(size 1.27 1.27)
					(thickness 0.15)
				)
				(justify left bottom)
				(hide yes)
			)
		)
		(property "Datasheet" "https://product.tdk.com/en/search/capacitor/ceramic/mlcc/info?part_no=C1005X5R1E474M050BB"
			(at 222.25 97.79 0)
			(effects
				(font
					(size 1.27 1.27)
					(thickness 0.15)
				)
				(justify left bottom)
				(hide yes)
			)
		)
		(property "Description" ""
			(at 207.01 77.47 0)
			(effects
				(font
					(size 1.27 1.27)
				)
			)
		)
		(property "Manufacturer" "TDK"
			(at 227.33 97.79 0)
			(effects
				(font
					(size 1.27 1.27)
					(thickness 0.15)
				)
				(justify left bottom)
				(hide yes)
			)
		)
		(property "MPN" "C1005X5R1E474M050BB"
			(at 224.79 97.79 0)
			(effects
				(font
					(size 1.27 1.27)
					(thickness 0.15)
				)
				(justify left bottom)
				(hide yes)
			)
		)
		(property "Val" "470n"
			(at 207.645 81.915 90)
			(effects
				(font
					(size 1.27 1.27)
					(thickness 0.15)
				)
				(justify right)
			)
		)
		(property "License" "Apache-2.0"
			(at 229.87 97.79 0)
			(effects
				(font
					(size 1.27 1.27)
					(thickness 0.15)
				)
				(justify left bottom)
				(hide yes)
			)
		)
		(property "Author" "Antmicro"
			(at 232.41 97.79 0)
			(effects
				(font
					(size 1.27 1.27)
					(thickness 0.15)
				)
				(justify left bottom)
				(hide yes)
			)
		)
		(property "Voltage" ""
			(at 234.95 97.79 0)
			(effects
				(font
					(size 1.27 1.27)
				)
				(justify left bottom)
				(hide yes)
			)
		)
		(property "Dielectric" ""
			(at 237.49 97.79 0)
			(effects
				(font
					(size 1.27 1.27)
				)
				(justify left bottom)
				(hide yes)
			)
		)
		(pin "1"
		)
		(pin "2"
		)
		(instances
			(project "sodimm-ddr5-tester"
				(path ""
					(reference "C143")
					(unit 1)
				)
			)
		)
	)
	(symbol
		(lib_id "antmicroCapacitors0402:C_10n_0402")
		(at 198.755 77.47 90)
		(mirror x)
		(unit 1)
		(exclude_from_sim no)
		(in_bom yes)
		(on_board yes)
		(dnp no)
		(property "Reference" "C140"
			(at 199.39 78.105 90)
			(effects
				(font
					(size 1.27 1.27)
				)
				(justify right)
			)
		)
		(property "Value" "C_10n_0402"
			(at 208.915 97.79 0)
			(effects
				(font
					(size 1.27 1.27)
					(thickness 0.15)
				)
				(justify left bottom)
				(hide yes)
			)
		)
		(property "Footprint" "antmicro-footprints:C_0402_1005Metric"
			(at 211.455 97.79 0)
			(effects
				(font
					(size 1.27 1.27)
					(thickness 0.15)
				)
				(justify left bottom)
				(hide yes)
			)
		)
		(property "Datasheet" "https://www.murata.com/products/productdetail?partno=GRM155R71H103KA88%23"
			(at 213.995 97.79 0)
			(effects
				(font
					(size 1.27 1.27)
					(thickness 0.15)
				)
				(justify left bottom)
				(hide yes)
			)
		)
		(property "Description" ""
			(at 198.755 77.47 0)
			(effects
				(font
					(size 1.27 1.27)
				)
			)
		)
		(property "Manufacturer" "Murata"
			(at 219.075 97.79 0)
			(effects
				(font
					(size 1.27 1.27)
					(thickness 0.15)
				)
				(justify left bottom)
				(hide yes)
			)
		)
		(property "MPN" "GRM155R71H103KA88D"
			(at 216.535 97.79 0)
			(effects
				(font
					(size 1.27 1.27)
					(thickness 0.15)
				)
				(justify left bottom)
				(hide yes)
			)
		)
		(property "Val" "10n"
			(at 199.39 81.915 90)
			(effects
				(font
					(size 1.27 1.27)
					(thickness 0.15)
				)
				(justify right)
			)
		)
		(property "License" "Apache-2.0"
			(at 221.615 97.79 0)
			(effects
				(font
					(size 1.27 1.27)
					(thickness 0.15)
				)
				(justify left bottom)
				(hide yes)
			)
		)
		(property "Author" "Antmicro"
			(at 224.155 97.79 0)
			(effects
				(font
					(size 1.27 1.27)
					(thickness 0.15)
				)
				(justify left bottom)
				(hide yes)
			)
		)
		(property "Voltage" "50V"
			(at 226.695 97.79 0)
			(effects
				(font
					(size 1.27 1.27)
				)
				(justify left bottom)
				(hide yes)
			)
		)
		(property "Dielectric" "X7R"
			(at 229.235 97.79 0)
			(effects
				(font
					(size 1.27 1.27)
				)
				(justify left bottom)
				(hide yes)
			)
		)
		(pin "1"
		)
		(pin "2"
		)
		(instances
			(project "sodimm-ddr5-tester"
				(path ""
					(reference "C140")
					(unit 1)
				)
			)
		)
	)
	(symbol
		(lib_id "antmicroCapacitors0402:C_10n_0402")
		(at 190.5 77.47 90)
		(mirror x)
		(unit 1)
		(exclude_from_sim no)
		(in_bom yes)
		(on_board yes)
		(dnp no)
		(property "Reference" "C136"
			(at 191.135 78.105 90)
			(effects
				(font
					(size 1.27 1.27)
				)
				(justify right)
			)
		)
		(property "Value" "C_10n_0402"
			(at 200.66 97.79 0)
			(effects
				(font
					(size 1.27 1.27)
					(thickness 0.15)
				)
				(justify left bottom)
				(hide yes)
			)
		)
		(property "Footprint" "antmicro-footprints:C_0402_1005Metric"
			(at 203.2 97.79 0)
			(effects
				(font
					(size 1.27 1.27)
					(thickness 0.15)
				)
				(justify left bottom)
				(hide yes)
			)
		)
		(property "Datasheet" "https://www.murata.com/products/productdetail?partno=GRM155R71H103KA88%23"
			(at 205.74 97.79 0)
			(effects
				(font
					(size 1.27 1.27)
					(thickness 0.15)
				)
				(justify left bottom)
				(hide yes)
			)
		)
		(property "Description" ""
			(at 190.5 77.47 0)
			(effects
				(font
					(size 1.27 1.27)
				)
			)
		)
		(property "Manufacturer" "Murata"
			(at 210.82 97.79 0)
			(effects
				(font
					(size 1.27 1.27)
					(thickness 0.15)
				)
				(justify left bottom)
				(hide yes)
			)
		)
		(property "MPN" "GRM155R71H103KA88D"
			(at 208.28 97.79 0)
			(effects
				(font
					(size 1.27 1.27)
					(thickness 0.15)
				)
				(justify left bottom)
				(hide yes)
			)
		)
		(property "Val" "10n"
			(at 191.135 81.915 90)
			(effects
				(font
					(size 1.27 1.27)
					(thickness 0.15)
				)
				(justify right)
			)
		)
		(property "License" "Apache-2.0"
			(at 213.36 97.79 0)
			(effects
				(font
					(size 1.27 1.27)
					(thickness 0.15)
				)
				(justify left bottom)
				(hide yes)
			)
		)
		(property "Author" "Antmicro"
			(at 215.9 97.79 0)
			(effects
				(font
					(size 1.27 1.27)
					(thickness 0.15)
				)
				(justify left bottom)
				(hide yes)
			)
		)
		(property "Voltage" "50V"
			(at 218.44 97.79 0)
			(effects
				(font
					(size 1.27 1.27)
				)
				(justify left bottom)
				(hide yes)
			)
		)
		(property "Dielectric" "X7R"
			(at 220.98 97.79 0)
			(effects
				(font
					(size 1.27 1.27)
				)
				(justify left bottom)
				(hide yes)
			)
		)
		(pin "1"
		)
		(pin "2"
		)
		(instances
			(project "sodimm-ddr5-tester"
				(path ""
					(reference "C136")
					(unit 1)
				)
			)
		)
	)
	(symbol
		(lib_id "antmicroCapacitors0402:C_10n_0402")
		(at 198.755 56.515 90)
		(mirror x)
		(unit 1)
		(exclude_from_sim no)
		(in_bom yes)
		(on_board yes)
		(dnp no)
		(property "Reference" "C153"
			(at 198.12 57.15 90)
			(effects
				(font
					(size 1.27 1.27)
				)
				(justify left)
			)
		)
		(property "Value" "C_10n_0402"
			(at 208.915 76.835 0)
			(effects
				(font
					(size 1.27 1.27)
					(thickness 0.15)
				)
				(justify left bottom)
				(hide yes)
			)
		)
		(property "Footprint" "antmicro-footprints:C_0402_1005Metric"
			(at 211.455 76.835 0)
			(effects
				(font
					(size 1.27 1.27)
					(thickness 0.15)
				)
				(justify left bottom)
				(hide yes)
			)
		)
		(property "Datasheet" "https://www.murata.com/products/productdetail?partno=GRM155R71H103KA88%23"
			(at 213.995 76.835 0)
			(effects
				(font
					(size 1.27 1.27)
					(thickness 0.15)
				)
				(justify left bottom)
				(hide yes)
			)
		)
		(property "Description" ""
			(at 198.755 56.515 0)
			(effects
				(font
					(size 1.27 1.27)
				)
			)
		)
		(property "Manufacturer" "Murata"
			(at 219.075 76.835 0)
			(effects
				(font
					(size 1.27 1.27)
					(thickness 0.15)
				)
				(justify left bottom)
				(hide yes)
			)
		)
		(property "MPN" "GRM155R71H103KA88D"
			(at 216.535 76.835 0)
			(effects
				(font
					(size 1.27 1.27)
					(thickness 0.15)
				)
				(justify left bottom)
				(hide yes)
			)
		)
		(property "Val" "10n"
			(at 198.12 60.96 90)
			(effects
				(font
					(size 1.27 1.27)
					(thickness 0.15)
				)
				(justify left)
			)
		)
		(property "License" "Apache-2.0"
			(at 221.615 76.835 0)
			(effects
				(font
					(size 1.27 1.27)
					(thickness 0.15)
				)
				(justify left bottom)
				(hide yes)
			)
		)
		(property "Author" "Antmicro"
			(at 224.155 76.835 0)
			(effects
				(font
					(size 1.27 1.27)
					(thickness 0.15)
				)
				(justify left bottom)
				(hide yes)
			)
		)
		(property "Voltage" "50V"
			(at 226.695 76.835 0)
			(effects
				(font
					(size 1.27 1.27)
				)
				(justify left bottom)
				(hide yes)
			)
		)
		(property "Dielectric" "X7R"
			(at 229.235 76.835 0)
			(effects
				(font
					(size 1.27 1.27)
				)
				(justify left bottom)
				(hide yes)
			)
		)
		(pin "1"
		)
		(pin "2"
		)
		(instances
			(project "sodimm-ddr5-tester"
				(path ""
					(reference "C153")
					(unit 1)
				)
			)
		)
	)
	(symbol
		(lib_id "antmicroCapacitors0402:C_10n_0402")
		(at 190.5 56.515 90)
		(mirror x)
		(unit 1)
		(exclude_from_sim no)
		(in_bom yes)
		(on_board yes)
		(dnp no)
		(property "Reference" "C156"
			(at 189.865 57.15 90)
			(effects
				(font
					(size 1.27 1.27)
				)
				(justify left)
			)
		)
		(property "Value" "C_10n_0402"
			(at 200.66 76.835 0)
			(effects
				(font
					(size 1.27 1.27)
					(thickness 0.15)
				)
				(justify left bottom)
				(hide yes)
			)
		)
		(property "Footprint" "antmicro-footprints:C_0402_1005Metric"
			(at 203.2 76.835 0)
			(effects
				(font
					(size 1.27 1.27)
					(thickness 0.15)
				)
				(justify left bottom)
				(hide yes)
			)
		)
		(property "Datasheet" "https://www.murata.com/products/productdetail?partno=GRM155R71H103KA88%23"
			(at 205.74 76.835 0)
			(effects
				(font
					(size 1.27 1.27)
					(thickness 0.15)
				)
				(justify left bottom)
				(hide yes)
			)
		)
		(property "Description" ""
			(at 190.5 56.515 0)
			(effects
				(font
					(size 1.27 1.27)
				)
			)
		)
		(property "Manufacturer" "Murata"
			(at 210.82 76.835 0)
			(effects
				(font
					(size 1.27 1.27)
					(thickness 0.15)
				)
				(justify left bottom)
				(hide yes)
			)
		)
		(property "MPN" "GRM155R71H103KA88D"
			(at 208.28 76.835 0)
			(effects
				(font
					(size 1.27 1.27)
					(thickness 0.15)
				)
				(justify left bottom)
				(hide yes)
			)
		)
		(property "Val" "10n"
			(at 189.865 60.96 90)
			(effects
				(font
					(size 1.27 1.27)
					(thickness 0.15)
				)
				(justify left)
			)
		)
		(property "License" "Apache-2.0"
			(at 213.36 76.835 0)
			(effects
				(font
					(size 1.27 1.27)
					(thickness 0.15)
				)
				(justify left bottom)
				(hide yes)
			)
		)
		(property "Author" "Antmicro"
			(at 215.9 76.835 0)
			(effects
				(font
					(size 1.27 1.27)
					(thickness 0.15)
				)
				(justify left bottom)
				(hide yes)
			)
		)
		(property "Voltage" "50V"
			(at 218.44 76.835 0)
			(effects
				(font
					(size 1.27 1.27)
				)
				(justify left bottom)
				(hide yes)
			)
		)
		(property "Dielectric" "X7R"
			(at 220.98 76.835 0)
			(effects
				(font
					(size 1.27 1.27)
				)
				(justify left bottom)
				(hide yes)
			)
		)
		(pin "1"
		)
		(pin "2"
		)
		(instances
			(project "sodimm-ddr5-tester"
				(path ""
					(reference "C156")
					(unit 1)
				)
			)
		)
	)
	(symbol
		(lib_id "antmicroCapacitors0402:C_10n_0402")
		(at 215.265 56.515 90)
		(mirror x)
		(unit 1)
		(exclude_from_sim no)
		(in_bom yes)
		(on_board yes)
		(dnp no)
		(property "Reference" "C150"
			(at 214.63 57.15 90)
			(effects
				(font
					(size 1.27 1.27)
				)
				(justify left)
			)
		)
		(property "Value" "C_10n_0402"
			(at 225.425 76.835 0)
			(effects
				(font
					(size 1.27 1.27)
					(thickness 0.15)
				)
				(justify left bottom)
				(hide yes)
			)
		)
		(property "Footprint" "antmicro-footprints:C_0402_1005Metric"
			(at 227.965 76.835 0)
			(effects
				(font
					(size 1.27 1.27)
					(thickness 0.15)
				)
				(justify left bottom)
				(hide yes)
			)
		)
		(property "Datasheet" "https://www.murata.com/products/productdetail?partno=GRM155R71H103KA88%23"
			(at 230.505 76.835 0)
			(effects
				(font
					(size 1.27 1.27)
					(thickness 0.15)
				)
				(justify left bottom)
				(hide yes)
			)
		)
		(property "Description" ""
			(at 215.265 56.515 0)
			(effects
				(font
					(size 1.27 1.27)
				)
			)
		)
		(property "Manufacturer" "Murata"
			(at 235.585 76.835 0)
			(effects
				(font
					(size 1.27 1.27)
					(thickness 0.15)
				)
				(justify left bottom)
				(hide yes)
			)
		)
		(property "MPN" "GRM155R71H103KA88D"
			(at 233.045 76.835 0)
			(effects
				(font
					(size 1.27 1.27)
					(thickness 0.15)
				)
				(justify left bottom)
				(hide yes)
			)
		)
		(property "Val" "10n"
			(at 214.63 60.96 90)
			(effects
				(font
					(size 1.27 1.27)
					(thickness 0.15)
				)
				(justify left)
			)
		)
		(property "License" "Apache-2.0"
			(at 238.125 76.835 0)
			(effects
				(font
					(size 1.27 1.27)
					(thickness 0.15)
				)
				(justify left bottom)
				(hide yes)
			)
		)
		(property "Author" "Antmicro"
			(at 240.665 76.835 0)
			(effects
				(font
					(size 1.27 1.27)
					(thickness 0.15)
				)
				(justify left bottom)
				(hide yes)
			)
		)
		(property "Voltage" "50V"
			(at 243.205 76.835 0)
			(effects
				(font
					(size 1.27 1.27)
				)
				(justify left bottom)
				(hide yes)
			)
		)
		(property "Dielectric" "X7R"
			(at 245.745 76.835 0)
			(effects
				(font
					(size 1.27 1.27)
				)
				(justify left bottom)
				(hide yes)
			)
		)
		(pin "1"
		)
		(pin "2"
		)
		(instances
			(project "sodimm-ddr5-tester"
				(path ""
					(reference "C150")
					(unit 1)
				)
			)
		)
	)
	(symbol
		(lib_id "antmicroCapacitors0402:C_10n_0402")
		(at 207.01 56.515 90)
		(mirror x)
		(unit 1)
		(exclude_from_sim no)
		(in_bom yes)
		(on_board yes)
		(dnp no)
		(property "Reference" "C151"
			(at 206.375 57.15 90)
			(effects
				(font
					(size 1.27 1.27)
				)
				(justify left)
			)
		)
		(property "Value" "C_10n_0402"
			(at 217.17 76.835 0)
			(effects
				(font
					(size 1.27 1.27)
					(thickness 0.15)
				)
				(justify left bottom)
				(hide yes)
			)
		)
		(property "Footprint" "antmicro-footprints:C_0402_1005Metric"
			(at 219.71 76.835 0)
			(effects
				(font
					(size 1.27 1.27)
					(thickness 0.15)
				)
				(justify left bottom)
				(hide yes)
			)
		)
		(property "Datasheet" "https://www.murata.com/products/productdetail?partno=GRM155R71H103KA88%23"
			(at 222.25 76.835 0)
			(effects
				(font
					(size 1.27 1.27)
					(thickness 0.15)
				)
				(justify left bottom)
				(hide yes)
			)
		)
		(property "Description" ""
			(at 207.01 56.515 0)
			(effects
				(font
					(size 1.27 1.27)
				)
			)
		)
		(property "Manufacturer" "Murata"
			(at 227.33 76.835 0)
			(effects
				(font
					(size 1.27 1.27)
					(thickness 0.15)
				)
				(justify left bottom)
				(hide yes)
			)
		)
		(property "MPN" "GRM155R71H103KA88D"
			(at 224.79 76.835 0)
			(effects
				(font
					(size 1.27 1.27)
					(thickness 0.15)
				)
				(justify left bottom)
				(hide yes)
			)
		)
		(property "Val" "10n"
			(at 206.375 60.96 90)
			(effects
				(font
					(size 1.27 1.27)
					(thickness 0.15)
				)
				(justify left)
			)
		)
		(property "License" "Apache-2.0"
			(at 229.87 76.835 0)
			(effects
				(font
					(size 1.27 1.27)
					(thickness 0.15)
				)
				(justify left bottom)
				(hide yes)
			)
		)
		(property "Author" "Antmicro"
			(at 232.41 76.835 0)
			(effects
				(font
					(size 1.27 1.27)
					(thickness 0.15)
				)
				(justify left bottom)
				(hide yes)
			)
		)
		(property "Voltage" "50V"
			(at 234.95 76.835 0)
			(effects
				(font
					(size 1.27 1.27)
				)
				(justify left bottom)
				(hide yes)
			)
		)
		(property "Dielectric" "X7R"
			(at 237.49 76.835 0)
			(effects
				(font
					(size 1.27 1.27)
				)
				(justify left bottom)
				(hide yes)
			)
		)
		(pin "1"
		)
		(pin "2"
		)
		(instances
			(project "sodimm-ddr5-tester"
				(path ""
					(reference "C151")
					(unit 1)
				)
			)
		)
	)
	(symbol
		(lib_id "antmicroCapacitors0402:C_4u7_0402")
		(at 104.14 72.39 270)
		(unit 1)
		(exclude_from_sim no)
		(in_bom yes)
		(on_board yes)
		(dnp no)
		(property "Reference" "C155"
			(at 104.775 73.025 90)
			(effects
				(font
					(size 1.27 1.27)
				)
				(justify left)
			)
		)
		(property "Value" "C_4u7_0402"
			(at 93.98 92.71 0)
			(effects
				(font
					(size 1.27 1.27)
					(thickness 0.15)
				)
				(justify left bottom)
				(hide yes)
			)
		)
		(property "Footprint" "antmicro-footprints:C_0402_1005Metric"
			(at 91.44 92.71 0)
			(effects
				(font
					(size 1.27 1.27)
					(thickness 0.15)
				)
				(justify left bottom)
				(hide yes)
			)
		)
		(property "Datasheet" "https://www.murata.com/products/productdetail?partno=GRM155R61A475MEAA%23"
			(at 88.9 92.71 0)
			(effects
				(font
					(size 1.27 1.27)
					(thickness 0.15)
				)
				(justify left bottom)
				(hide yes)
			)
		)
		(property "Description" ""
			(at 104.14 72.39 0)
			(effects
				(font
					(size 1.27 1.27)
				)
			)
		)
		(property "Manufacturer" "Murata"
			(at 83.82 92.71 0)
			(effects
				(font
					(size 1.27 1.27)
					(thickness 0.15)
				)
				(justify left bottom)
				(hide yes)
			)
		)
		(property "MPN" "GRM155R61A475MEAAD"
			(at 86.36 92.71 0)
			(effects
				(font
					(size 1.27 1.27)
					(thickness 0.15)
				)
				(justify left bottom)
				(hide yes)
			)
		)
		(property "Val" "4u7"
			(at 104.775 76.835 90)
			(effects
				(font
					(size 1.27 1.27)
					(thickness 0.15)
				)
				(justify left)
			)
		)
		(property "License" "Apache-2.0"
			(at 81.28 92.71 0)
			(effects
				(font
					(size 1.27 1.27)
					(thickness 0.15)
				)
				(justify left bottom)
				(hide yes)
			)
		)
		(property "Author" "Antmicro"
			(at 78.74 92.71 0)
			(effects
				(font
					(size 1.27 1.27)
					(thickness 0.15)
				)
				(justify left bottom)
				(hide yes)
			)
		)
		(property "Voltage" ""
			(at 76.2 92.71 0)
			(effects
				(font
					(size 1.27 1.27)
				)
				(justify left bottom)
				(hide yes)
			)
		)
		(property "Dielectric" ""
			(at 73.66 92.71 0)
			(effects
				(font
					(size 1.27 1.27)
				)
				(justify left bottom)
				(hide yes)
			)
		)
		(pin "1"
		)
		(pin "2"
		)
		(instances
			(project "sodimm-ddr5-tester"
				(path ""
					(reference "C155")
					(unit 1)
				)
			)
		)
	)
	(symbol
		(lib_id "antmicroCapacitors0402:C_470n_0402")
		(at 223.52 56.515 90)
		(mirror x)
		(unit 1)
		(exclude_from_sim no)
		(in_bom yes)
		(on_board yes)
		(dnp no)
		(property "Reference" "C149"
			(at 222.885 57.15 90)
			(effects
				(font
					(size 1.27 1.27)
				)
				(justify left)
			)
		)
		(property "Value" "C_470n_0402"
			(at 233.68 76.835 0)
			(effects
				(font
					(size 1.27 1.27)
					(thickness 0.15)
				)
				(justify left bottom)
				(hide yes)
			)
		)
		(property "Footprint" "antmicro-footprints:C_0402_1005Metric"
			(at 236.22 76.835 0)
			(effects
				(font
					(size 1.27 1.27)
					(thickness 0.15)
				)
				(justify left bottom)
				(hide yes)
			)
		)
		(property "Datasheet" "https://product.tdk.com/en/search/capacitor/ceramic/mlcc/info?part_no=C1005X5R1E474M050BB"
			(at 238.76 76.835 0)
			(effects
				(font
					(size 1.27 1.27)
					(thickness 0.15)
				)
				(justify left bottom)
				(hide yes)
			)
		)
		(property "Description" ""
			(at 223.52 56.515 0)
			(effects
				(font
					(size 1.27 1.27)
				)
			)
		)
		(property "Manufacturer" "TDK"
			(at 243.84 76.835 0)
			(effects
				(font
					(size 1.27 1.27)
					(thickness 0.15)
				)
				(justify left bottom)
				(hide yes)
			)
		)
		(property "MPN" "C1005X5R1E474M050BB"
			(at 241.3 76.835 0)
			(effects
				(font
					(size 1.27 1.27)
					(thickness 0.15)
				)
				(justify left bottom)
				(hide yes)
			)
		)
		(property "Val" "470n"
			(at 222.885 60.96 90)
			(effects
				(font
					(size 1.27 1.27)
					(thickness 0.15)
				)
				(justify left)
			)
		)
		(property "License" "Apache-2.0"
			(at 246.38 76.835 0)
			(effects
				(font
					(size 1.27 1.27)
					(thickness 0.15)
				)
				(justify left bottom)
				(hide yes)
			)
		)
		(property "Author" "Antmicro"
			(at 248.92 76.835 0)
			(effects
				(font
					(size 1.27 1.27)
					(thickness 0.15)
				)
				(justify left bottom)
				(hide yes)
			)
		)
		(property "Voltage" ""
			(at 251.46 76.835 0)
			(effects
				(font
					(size 1.27 1.27)
				)
				(justify left bottom)
				(hide yes)
			)
		)
		(property "Dielectric" ""
			(at 254 76.835 0)
			(effects
				(font
					(size 1.27 1.27)
				)
				(justify left bottom)
				(hide yes)
			)
		)
		(pin "1"
		)
		(pin "2"
		)
		(instances
			(project "sodimm-ddr5-tester"
				(path ""
					(reference "C149")
					(unit 1)
				)
			)
		)
	)
	(symbol
		(lib_id "antmicroCapacitors0402:C_4u7_0402")
		(at 256.54 56.515 90)
		(mirror x)
		(unit 1)
		(exclude_from_sim no)
		(in_bom yes)
		(on_board yes)
		(dnp no)
		(property "Reference" "C139"
			(at 255.905 57.15 90)
			(effects
				(font
					(size 1.27 1.27)
				)
				(justify left)
			)
		)
		(property "Value" "C_4u7_0402"
			(at 266.7 76.835 0)
			(effects
				(font
					(size 1.27 1.27)
					(thickness 0.15)
				)
				(justify left bottom)
				(hide yes)
			)
		)
		(property "Footprint" "antmicro-footprints:C_0402_1005Metric"
			(at 269.24 76.835 0)
			(effects
				(font
					(size 1.27 1.27)
					(thickness 0.15)
				)
				(justify left bottom)
				(hide yes)
			)
		)
		(property "Datasheet" "https://www.murata.com/products/productdetail?partno=GRM155R61A475MEAA%23"
			(at 271.78 76.835 0)
			(effects
				(font
					(size 1.27 1.27)
					(thickness 0.15)
				)
				(justify left bottom)
				(hide yes)
			)
		)
		(property "Description" ""
			(at 256.54 56.515 0)
			(effects
				(font
					(size 1.27 1.27)
				)
			)
		)
		(property "Manufacturer" "Murata"
			(at 276.86 76.835 0)
			(effects
				(font
					(size 1.27 1.27)
					(thickness 0.15)
				)
				(justify left bottom)
				(hide yes)
			)
		)
		(property "MPN" "GRM155R61A475MEAAD"
			(at 274.32 76.835 0)
			(effects
				(font
					(size 1.27 1.27)
					(thickness 0.15)
				)
				(justify left bottom)
				(hide yes)
			)
		)
		(property "Val" "4u7"
			(at 255.905 60.96 90)
			(effects
				(font
					(size 1.27 1.27)
					(thickness 0.15)
				)
				(justify left)
			)
		)
		(property "License" "Apache-2.0"
			(at 279.4 76.835 0)
			(effects
				(font
					(size 1.27 1.27)
					(thickness 0.15)
				)
				(justify left bottom)
				(hide yes)
			)
		)
		(property "Author" "Antmicro"
			(at 281.94 76.835 0)
			(effects
				(font
					(size 1.27 1.27)
					(thickness 0.15)
				)
				(justify left bottom)
				(hide yes)
			)
		)
		(property "Voltage" ""
			(at 284.48 76.835 0)
			(effects
				(font
					(size 1.27 1.27)
				)
				(justify left bottom)
				(hide yes)
			)
		)
		(property "Dielectric" ""
			(at 287.02 76.835 0)
			(effects
				(font
					(size 1.27 1.27)
				)
				(justify left bottom)
				(hide yes)
			)
		)
		(pin "1"
		)
		(pin "2"
		)
		(instances
			(project "sodimm-ddr5-tester"
				(path ""
					(reference "C139")
					(unit 1)
				)
			)
		)
	)
	(symbol
		(lib_id "antmicroCapacitors0402:C_470n_0402")
		(at 248.285 56.515 90)
		(mirror x)
		(unit 1)
		(exclude_from_sim no)
		(in_bom yes)
		(on_board yes)
		(dnp no)
		(property "Reference" "C142"
			(at 247.65 57.15 90)
			(effects
				(font
					(size 1.27 1.27)
				)
				(justify left)
			)
		)
		(property "Value" "C_470n_0402"
			(at 258.445 76.835 0)
			(effects
				(font
					(size 1.27 1.27)
					(thickness 0.15)
				)
				(justify left bottom)
				(hide yes)
			)
		)
		(property "Footprint" "antmicro-footprints:C_0402_1005Metric"
			(at 260.985 76.835 0)
			(effects
				(font
					(size 1.27 1.27)
					(thickness 0.15)
				)
				(justify left bottom)
				(hide yes)
			)
		)
		(property "Datasheet" "https://product.tdk.com/en/search/capacitor/ceramic/mlcc/info?part_no=C1005X5R1E474M050BB"
			(at 263.525 76.835 0)
			(effects
				(font
					(size 1.27 1.27)
					(thickness 0.15)
				)
				(justify left bottom)
				(hide yes)
			)
		)
		(property "Description" ""
			(at 248.285 56.515 0)
			(effects
				(font
					(size 1.27 1.27)
				)
			)
		)
		(property "Manufacturer" "TDK"
			(at 268.605 76.835 0)
			(effects
				(font
					(size 1.27 1.27)
					(thickness 0.15)
				)
				(justify left bottom)
				(hide yes)
			)
		)
		(property "MPN" "C1005X5R1E474M050BB"
			(at 266.065 76.835 0)
			(effects
				(font
					(size 1.27 1.27)
					(thickness 0.15)
				)
				(justify left bottom)
				(hide yes)
			)
		)
		(property "Val" "470n"
			(at 247.65 60.96 90)
			(effects
				(font
					(size 1.27 1.27)
					(thickness 0.15)
				)
				(justify left)
			)
		)
		(property "License" "Apache-2.0"
			(at 271.145 76.835 0)
			(effects
				(font
					(size 1.27 1.27)
					(thickness 0.15)
				)
				(justify left bottom)
				(hide yes)
			)
		)
		(property "Author" "Antmicro"
			(at 273.685 76.835 0)
			(effects
				(font
					(size 1.27 1.27)
					(thickness 0.15)
				)
				(justify left bottom)
				(hide yes)
			)
		)
		(property "Voltage" ""
			(at 276.225 76.835 0)
			(effects
				(font
					(size 1.27 1.27)
				)
				(justify left bottom)
				(hide yes)
			)
		)
		(property "Dielectric" ""
			(at 278.765 76.835 0)
			(effects
				(font
					(size 1.27 1.27)
				)
				(justify left bottom)
				(hide yes)
			)
		)
		(pin "1"
		)
		(pin "2"
		)
		(instances
			(project "sodimm-ddr5-tester"
				(path ""
					(reference "C142")
					(unit 1)
				)
			)
		)
	)
	(symbol
		(lib_id "antmicroCapacitors0402:C_470n_0402")
		(at 240.03 56.515 90)
		(mirror x)
		(unit 1)
		(exclude_from_sim no)
		(in_bom yes)
		(on_board yes)
		(dnp no)
		(property "Reference" "C145"
			(at 239.395 57.15 90)
			(effects
				(font
					(size 1.27 1.27)
				)
				(justify left)
			)
		)
		(property "Value" "C_470n_0402"
			(at 250.19 76.835 0)
			(effects
				(font
					(size 1.27 1.27)
					(thickness 0.15)
				)
				(justify left bottom)
				(hide yes)
			)
		)
		(property "Footprint" "antmicro-footprints:C_0402_1005Metric"
			(at 252.73 76.835 0)
			(effects
				(font
					(size 1.27 1.27)
					(thickness 0.15)
				)
				(justify left bottom)
				(hide yes)
			)
		)
		(property "Datasheet" "https://product.tdk.com/en/search/capacitor/ceramic/mlcc/info?part_no=C1005X5R1E474M050BB"
			(at 255.27 76.835 0)
			(effects
				(font
					(size 1.27 1.27)
					(thickness 0.15)
				)
				(justify left bottom)
				(hide yes)
			)
		)
		(property "Description" ""
			(at 240.03 56.515 0)
			(effects
				(font
					(size 1.27 1.27)
				)
			)
		)
		(property "Manufacturer" "TDK"
			(at 260.35 76.835 0)
			(effects
				(font
					(size 1.27 1.27)
					(thickness 0.15)
				)
				(justify left bottom)
				(hide yes)
			)
		)
		(property "MPN" "C1005X5R1E474M050BB"
			(at 257.81 76.835 0)
			(effects
				(font
					(size 1.27 1.27)
					(thickness 0.15)
				)
				(justify left bottom)
				(hide yes)
			)
		)
		(property "Val" "470n"
			(at 239.395 60.96 90)
			(effects
				(font
					(size 1.27 1.27)
					(thickness 0.15)
				)
				(justify left)
			)
		)
		(property "License" "Apache-2.0"
			(at 262.89 76.835 0)
			(effects
				(font
					(size 1.27 1.27)
					(thickness 0.15)
				)
				(justify left bottom)
				(hide yes)
			)
		)
		(property "Author" "Antmicro"
			(at 265.43 76.835 0)
			(effects
				(font
					(size 1.27 1.27)
					(thickness 0.15)
				)
				(justify left bottom)
				(hide yes)
			)
		)
		(property "Voltage" ""
			(at 267.97 76.835 0)
			(effects
				(font
					(size 1.27 1.27)
				)
				(justify left bottom)
				(hide yes)
			)
		)
		(property "Dielectric" ""
			(at 270.51 76.835 0)
			(effects
				(font
					(size 1.27 1.27)
				)
				(justify left bottom)
				(hide yes)
			)
		)
		(pin "1"
		)
		(pin "2"
		)
		(instances
			(project "sodimm-ddr5-tester"
				(path ""
					(reference "C145")
					(unit 1)
				)
			)
		)
	)
	(symbol
		(lib_id "antmicroCapacitors0402:C_470n_0402")
		(at 231.775 56.515 90)
		(mirror x)
		(unit 1)
		(exclude_from_sim no)
		(in_bom yes)
		(on_board yes)
		(dnp no)
		(property "Reference" "C148"
			(at 231.14 57.15 90)
			(effects
				(font
					(size 1.27 1.27)
				)
				(justify left)
			)
		)
		(property "Value" "C_470n_0402"
			(at 241.935 76.835 0)
			(effects
				(font
					(size 1.27 1.27)
					(thickness 0.15)
				)
				(justify left bottom)
				(hide yes)
			)
		)
		(property "Footprint" "antmicro-footprints:C_0402_1005Metric"
			(at 244.475 76.835 0)
			(effects
				(font
					(size 1.27 1.27)
					(thickness 0.15)
				)
				(justify left bottom)
				(hide yes)
			)
		)
		(property "Datasheet" "https://product.tdk.com/en/search/capacitor/ceramic/mlcc/info?part_no=C1005X5R1E474M050BB"
			(at 247.015 76.835 0)
			(effects
				(font
					(size 1.27 1.27)
					(thickness 0.15)
				)
				(justify left bottom)
				(hide yes)
			)
		)
		(property "Description" ""
			(at 231.775 56.515 0)
			(effects
				(font
					(size 1.27 1.27)
				)
			)
		)
		(property "Manufacturer" "TDK"
			(at 252.095 76.835 0)
			(effects
				(font
					(size 1.27 1.27)
					(thickness 0.15)
				)
				(justify left bottom)
				(hide yes)
			)
		)
		(property "MPN" "C1005X5R1E474M050BB"
			(at 249.555 76.835 0)
			(effects
				(font
					(size 1.27 1.27)
					(thickness 0.15)
				)
				(justify left bottom)
				(hide yes)
			)
		)
		(property "Val" "470n"
			(at 231.14 60.96 90)
			(effects
				(font
					(size 1.27 1.27)
					(thickness 0.15)
				)
				(justify left)
			)
		)
		(property "License" "Apache-2.0"
			(at 254.635 76.835 0)
			(effects
				(font
					(size 1.27 1.27)
					(thickness 0.15)
				)
				(justify left bottom)
				(hide yes)
			)
		)
		(property "Author" "Antmicro"
			(at 257.175 76.835 0)
			(effects
				(font
					(size 1.27 1.27)
					(thickness 0.15)
				)
				(justify left bottom)
				(hide yes)
			)
		)
		(property "Voltage" ""
			(at 259.715 76.835 0)
			(effects
				(font
					(size 1.27 1.27)
				)
				(justify left bottom)
				(hide yes)
			)
		)
		(property "Dielectric" ""
			(at 262.255 76.835 0)
			(effects
				(font
					(size 1.27 1.27)
				)
				(justify left bottom)
				(hide yes)
			)
		)
		(pin "1"
		)
		(pin "2"
		)
		(instances
			(project "sodimm-ddr5-tester"
				(path ""
					(reference "C148")
					(unit 1)
				)
			)
		)
	)
	(symbol
		(lib_id "antmicroCapacitors0402:C_4u7_0402")
		(at 112.395 72.39 270)
		(unit 1)
		(exclude_from_sim no)
		(in_bom yes)
		(on_board yes)
		(dnp no)
		(property "Reference" "C158"
			(at 113.03 73.025 90)
			(effects
				(font
					(size 1.27 1.27)
				)
				(justify left)
			)
		)
		(property "Value" "C_4u7_0402"
			(at 102.235 92.71 0)
			(effects
				(font
					(size 1.27 1.27)
					(thickness 0.15)
				)
				(justify left bottom)
				(hide yes)
			)
		)
		(property "Footprint" "antmicro-footprints:C_0402_1005Metric"
			(at 99.695 92.71 0)
			(effects
				(font
					(size 1.27 1.27)
					(thickness 0.15)
				)
				(justify left bottom)
				(hide yes)
			)
		)
		(property "Datasheet" "https://www.murata.com/products/productdetail?partno=GRM155R61A475MEAA%23"
			(at 97.155 92.71 0)
			(effects
				(font
					(size 1.27 1.27)
					(thickness 0.15)
				)
				(justify left bottom)
				(hide yes)
			)
		)
		(property "Description" ""
			(at 112.395 72.39 0)
			(effects
				(font
					(size 1.27 1.27)
				)
			)
		)
		(property "Manufacturer" "Murata"
			(at 92.075 92.71 0)
			(effects
				(font
					(size 1.27 1.27)
					(thickness 0.15)
				)
				(justify left bottom)
				(hide yes)
			)
		)
		(property "MPN" "GRM155R61A475MEAAD"
			(at 94.615 92.71 0)
			(effects
				(font
					(size 1.27 1.27)
					(thickness 0.15)
				)
				(justify left bottom)
				(hide yes)
			)
		)
		(property "Val" "4u7"
			(at 113.03 76.835 90)
			(effects
				(font
					(size 1.27 1.27)
					(thickness 0.15)
				)
				(justify left)
			)
		)
		(property "License" "Apache-2.0"
			(at 89.535 92.71 0)
			(effects
				(font
					(size 1.27 1.27)
					(thickness 0.15)
				)
				(justify left bottom)
				(hide yes)
			)
		)
		(property "Author" "Antmicro"
			(at 86.995 92.71 0)
			(effects
				(font
					(size 1.27 1.27)
					(thickness 0.15)
				)
				(justify left bottom)
				(hide yes)
			)
		)
		(property "Voltage" ""
			(at 84.455 92.71 0)
			(effects
				(font
					(size 1.27 1.27)
				)
				(justify left bottom)
				(hide yes)
			)
		)
		(property "Dielectric" ""
			(at 81.915 92.71 0)
			(effects
				(font
					(size 1.27 1.27)
				)
				(justify left bottom)
				(hide yes)
			)
		)
		(pin "1"
		)
		(pin "2"
		)
		(instances
			(project "sodimm-ddr5-tester"
				(path ""
					(reference "C158")
					(unit 1)
				)
			)
		)
	)
	(symbol
		(lib_id "antmicroCapacitors0402:C_4u7_0402")
		(at 95.885 72.39 270)
		(unit 1)
		(exclude_from_sim no)
		(in_bom yes)
		(on_board yes)
		(dnp no)
		(property "Reference" "C152"
			(at 96.52 73.025 90)
			(effects
				(font
					(size 1.27 1.27)
				)
				(justify left)
			)
		)
		(property "Value" "C_4u7_0402"
			(at 85.725 92.71 0)
			(effects
				(font
					(size 1.27 1.27)
					(thickness 0.15)
				)
				(justify left bottom)
				(hide yes)
			)
		)
		(property "Footprint" "antmicro-footprints:C_0402_1005Metric"
			(at 83.185 92.71 0)
			(effects
				(font
					(size 1.27 1.27)
					(thickness 0.15)
				)
				(justify left bottom)
				(hide yes)
			)
		)
		(property "Datasheet" "https://www.murata.com/products/productdetail?partno=GRM155R61A475MEAA%23"
			(at 80.645 92.71 0)
			(effects
				(font
					(size 1.27 1.27)
					(thickness 0.15)
				)
				(justify left bottom)
				(hide yes)
			)
		)
		(property "Description" ""
			(at 95.885 72.39 0)
			(effects
				(font
					(size 1.27 1.27)
				)
			)
		)
		(property "Manufacturer" "Murata"
			(at 75.565 92.71 0)
			(effects
				(font
					(size 1.27 1.27)
					(thickness 0.15)
				)
				(justify left bottom)
				(hide yes)
			)
		)
		(property "MPN" "GRM155R61A475MEAAD"
			(at 78.105 92.71 0)
			(effects
				(font
					(size 1.27 1.27)
					(thickness 0.15)
				)
				(justify left bottom)
				(hide yes)
			)
		)
		(property "Val" "4u7"
			(at 96.52 76.835 90)
			(effects
				(font
					(size 1.27 1.27)
					(thickness 0.15)
				)
				(justify left)
			)
		)
		(property "License" "Apache-2.0"
			(at 73.025 92.71 0)
			(effects
				(font
					(size 1.27 1.27)
					(thickness 0.15)
				)
				(justify left bottom)
				(hide yes)
			)
		)
		(property "Author" "Antmicro"
			(at 70.485 92.71 0)
			(effects
				(font
					(size 1.27 1.27)
					(thickness 0.15)
				)
				(justify left bottom)
				(hide yes)
			)
		)
		(property "Voltage" ""
			(at 67.945 92.71 0)
			(effects
				(font
					(size 1.27 1.27)
				)
				(justify left bottom)
				(hide yes)
			)
		)
		(property "Dielectric" ""
			(at 65.405 92.71 0)
			(effects
				(font
					(size 1.27 1.27)
				)
				(justify left bottom)
				(hide yes)
			)
		)
		(pin "1"
		)
		(pin "2"
		)
		(instances
			(project "sodimm-ddr5-tester"
				(path ""
					(reference "C152")
					(unit 1)
				)
			)
		)
	)
	(symbol
		(lib_id "antmicroCapacitors0402:C_4u7_0402")
		(at 79.375 51.435 270)
		(unit 1)
		(exclude_from_sim no)
		(in_bom yes)
		(on_board yes)
		(dnp no)
		(property "Reference" "C134"
			(at 80.01 52.07 90)
			(effects
				(font
					(size 1.27 1.27)
				)
				(justify left)
			)
		)
		(property "Value" "C_4u7_0402"
			(at 69.215 71.755 0)
			(effects
				(font
					(size 1.27 1.27)
					(thickness 0.15)
				)
				(justify left bottom)
				(hide yes)
			)
		)
		(property "Footprint" "antmicro-footprints:C_0402_1005Metric"
			(at 66.675 71.755 0)
			(effects
				(font
					(size 1.27 1.27)
					(thickness 0.15)
				)
				(justify left bottom)
				(hide yes)
			)
		)
		(property "Datasheet" "https://www.murata.com/products/productdetail?partno=GRM155R61A475MEAA%23"
			(at 64.135 71.755 0)
			(effects
				(font
					(size 1.27 1.27)
					(thickness 0.15)
				)
				(justify left bottom)
				(hide yes)
			)
		)
		(property "Description" ""
			(at 79.375 51.435 0)
			(effects
				(font
					(size 1.27 1.27)
				)
			)
		)
		(property "Manufacturer" "Murata"
			(at 59.055 71.755 0)
			(effects
				(font
					(size 1.27 1.27)
					(thickness 0.15)
				)
				(justify left bottom)
				(hide yes)
			)
		)
		(property "MPN" "GRM155R61A475MEAAD"
			(at 61.595 71.755 0)
			(effects
				(font
					(size 1.27 1.27)
					(thickness 0.15)
				)
				(justify left bottom)
				(hide yes)
			)
		)
		(property "Val" "4u7"
			(at 80.01 55.88 90)
			(effects
				(font
					(size 1.27 1.27)
					(thickness 0.15)
				)
				(justify left)
			)
		)
		(property "License" "Apache-2.0"
			(at 56.515 71.755 0)
			(effects
				(font
					(size 1.27 1.27)
					(thickness 0.15)
				)
				(justify left bottom)
				(hide yes)
			)
		)
		(property "Author" "Antmicro"
			(at 53.975 71.755 0)
			(effects
				(font
					(size 1.27 1.27)
					(thickness 0.15)
				)
				(justify left bottom)
				(hide yes)
			)
		)
		(property "Voltage" ""
			(at 51.435 71.755 0)
			(effects
				(font
					(size 1.27 1.27)
				)
				(justify left bottom)
				(hide yes)
			)
		)
		(property "Dielectric" ""
			(at 48.895 71.755 0)
			(effects
				(font
					(size 1.27 1.27)
				)
				(justify left bottom)
				(hide yes)
			)
		)
		(pin "1"
		)
		(pin "2"
		)
		(instances
			(project "sodimm-ddr5-tester"
				(path ""
					(reference "C134")
					(unit 1)
				)
			)
		)
	)
	(symbol
		(lib_id "antmicroCapacitors0402:C_470n_0402")
		(at 87.63 51.435 270)
		(unit 1)
		(exclude_from_sim no)
		(in_bom yes)
		(on_board yes)
		(dnp no)
		(property "Reference" "C138"
			(at 88.265 52.07 90)
			(effects
				(font
					(size 1.27 1.27)
				)
				(justify left)
			)
		)
		(property "Value" "C_470n_0402"
			(at 77.47 71.755 0)
			(effects
				(font
					(size 1.27 1.27)
					(thickness 0.15)
				)
				(justify left bottom)
				(hide yes)
			)
		)
		(property "Footprint" "antmicro-footprints:C_0402_1005Metric"
			(at 74.93 71.755 0)
			(effects
				(font
					(size 1.27 1.27)
					(thickness 0.15)
				)
				(justify left bottom)
				(hide yes)
			)
		)
		(property "Datasheet" "https://product.tdk.com/en/search/capacitor/ceramic/mlcc/info?part_no=C1005X5R1E474M050BB"
			(at 72.39 71.755 0)
			(effects
				(font
					(size 1.27 1.27)
					(thickness 0.15)
				)
				(justify left bottom)
				(hide yes)
			)
		)
		(property "Description" ""
			(at 87.63 51.435 0)
			(effects
				(font
					(size 1.27 1.27)
				)
			)
		)
		(property "Manufacturer" "TDK"
			(at 67.31 71.755 0)
			(effects
				(font
					(size 1.27 1.27)
					(thickness 0.15)
				)
				(justify left bottom)
				(hide yes)
			)
		)
		(property "MPN" "C1005X5R1E474M050BB"
			(at 69.85 71.755 0)
			(effects
				(font
					(size 1.27 1.27)
					(thickness 0.15)
				)
				(justify left bottom)
				(hide yes)
			)
		)
		(property "Val" "470n"
			(at 88.265 55.88 90)
			(effects
				(font
					(size 1.27 1.27)
					(thickness 0.15)
				)
				(justify left)
			)
		)
		(property "License" "Apache-2.0"
			(at 64.77 71.755 0)
			(effects
				(font
					(size 1.27 1.27)
					(thickness 0.15)
				)
				(justify left bottom)
				(hide yes)
			)
		)
		(property "Author" "Antmicro"
			(at 62.23 71.755 0)
			(effects
				(font
					(size 1.27 1.27)
					(thickness 0.15)
				)
				(justify left bottom)
				(hide yes)
			)
		)
		(property "Voltage" ""
			(at 59.69 71.755 0)
			(effects
				(font
					(size 1.27 1.27)
				)
				(justify left bottom)
				(hide yes)
			)
		)
		(property "Dielectric" ""
			(at 57.15 71.755 0)
			(effects
				(font
					(size 1.27 1.27)
				)
				(justify left bottom)
				(hide yes)
			)
		)
		(pin "1"
		)
		(pin "2"
		)
		(instances
			(project "sodimm-ddr5-tester"
				(path ""
					(reference "C138")
					(unit 1)
				)
			)
		)
	)
	(symbol
		(lib_id "antmicroCapacitors0402:C_10n_0402")
		(at 104.14 51.435 270)
		(unit 1)
		(exclude_from_sim no)
		(in_bom yes)
		(on_board yes)
		(dnp no)
		(property "Reference" "C144"
			(at 104.775 52.07 90)
			(effects
				(font
					(size 1.27 1.27)
				)
				(justify left)
			)
		)
		(property "Value" "C_10n_0402"
			(at 93.98 71.755 0)
			(effects
				(font
					(size 1.27 1.27)
					(thickness 0.15)
				)
				(justify left bottom)
				(hide yes)
			)
		)
		(property "Footprint" "antmicro-footprints:C_0402_1005Metric"
			(at 91.44 71.755 0)
			(effects
				(font
					(size 1.27 1.27)
					(thickness 0.15)
				)
				(justify left bottom)
				(hide yes)
			)
		)
		(property "Datasheet" "https://www.murata.com/products/productdetail?partno=GRM155R71H103KA88%23"
			(at 88.9 71.755 0)
			(effects
				(font
					(size 1.27 1.27)
					(thickness 0.15)
				)
				(justify left bottom)
				(hide yes)
			)
		)
		(property "Description" ""
			(at 104.14 51.435 0)
			(effects
				(font
					(size 1.27 1.27)
				)
			)
		)
		(property "Manufacturer" "Murata"
			(at 83.82 71.755 0)
			(effects
				(font
					(size 1.27 1.27)
					(thickness 0.15)
				)
				(justify left bottom)
				(hide yes)
			)
		)
		(property "MPN" "GRM155R71H103KA88D"
			(at 86.36 71.755 0)
			(effects
				(font
					(size 1.27 1.27)
					(thickness 0.15)
				)
				(justify left bottom)
				(hide yes)
			)
		)
		(property "Val" "10n"
			(at 104.775 55.88 90)
			(effects
				(font
					(size 1.27 1.27)
					(thickness 0.15)
				)
				(justify left)
			)
		)
		(property "License" "Apache-2.0"
			(at 81.28 71.755 0)
			(effects
				(font
					(size 1.27 1.27)
					(thickness 0.15)
				)
				(justify left bottom)
				(hide yes)
			)
		)
		(property "Author" "Antmicro"
			(at 78.74 71.755 0)
			(effects
				(font
					(size 1.27 1.27)
					(thickness 0.15)
				)
				(justify left bottom)
				(hide yes)
			)
		)
		(property "Voltage" "50V"
			(at 76.2 71.755 0)
			(effects
				(font
					(size 1.27 1.27)
				)
				(justify left bottom)
				(hide yes)
			)
		)
		(property "Dielectric" "X7R"
			(at 73.66 71.755 0)
			(effects
				(font
					(size 1.27 1.27)
				)
				(justify left bottom)
				(hide yes)
			)
		)
		(pin "1"
		)
		(pin "2"
		)
		(instances
			(project "sodimm-ddr5-tester"
				(path ""
					(reference "C144")
					(unit 1)
				)
			)
		)
	)
	(symbol
		(lib_id "antmicroCapacitors0402:C_10n_0402")
		(at 112.395 51.435 270)
		(unit 1)
		(exclude_from_sim no)
		(in_bom yes)
		(on_board yes)
		(dnp no)
		(property "Reference" "C147"
			(at 113.03 52.07 90)
			(effects
				(font
					(size 1.27 1.27)
				)
				(justify left)
			)
		)
		(property "Value" "C_10n_0402"
			(at 102.235 71.755 0)
			(effects
				(font
					(size 1.27 1.27)
					(thickness 0.15)
				)
				(justify left bottom)
				(hide yes)
			)
		)
		(property "Footprint" "antmicro-footprints:C_0402_1005Metric"
			(at 99.695 71.755 0)
			(effects
				(font
					(size 1.27 1.27)
					(thickness 0.15)
				)
				(justify left bottom)
				(hide yes)
			)
		)
		(property "Datasheet" "https://www.murata.com/products/productdetail?partno=GRM155R71H103KA88%23"
			(at 97.155 71.755 0)
			(effects
				(font
					(size 1.27 1.27)
					(thickness 0.15)
				)
				(justify left bottom)
				(hide yes)
			)
		)
		(property "Description" ""
			(at 112.395 51.435 0)
			(effects
				(font
					(size 1.27 1.27)
				)
			)
		)
		(property "Manufacturer" "Murata"
			(at 92.075 71.755 0)
			(effects
				(font
					(size 1.27 1.27)
					(thickness 0.15)
				)
				(justify left bottom)
				(hide yes)
			)
		)
		(property "MPN" "GRM155R71H103KA88D"
			(at 94.615 71.755 0)
			(effects
				(font
					(size 1.27 1.27)
					(thickness 0.15)
				)
				(justify left bottom)
				(hide yes)
			)
		)
		(property "Val" "10n"
			(at 113.03 55.88 90)
			(effects
				(font
					(size 1.27 1.27)
					(thickness 0.15)
				)
				(justify left)
			)
		)
		(property "License" "Apache-2.0"
			(at 89.535 71.755 0)
			(effects
				(font
					(size 1.27 1.27)
					(thickness 0.15)
				)
				(justify left bottom)
				(hide yes)
			)
		)
		(property "Author" "Antmicro"
			(at 86.995 71.755 0)
			(effects
				(font
					(size 1.27 1.27)
					(thickness 0.15)
				)
				(justify left bottom)
				(hide yes)
			)
		)
		(property "Voltage" "50V"
			(at 84.455 71.755 0)
			(effects
				(font
					(size 1.27 1.27)
				)
				(justify left bottom)
				(hide yes)
			)
		)
		(property "Dielectric" "X7R"
			(at 81.915 71.755 0)
			(effects
				(font
					(size 1.27 1.27)
				)
				(justify left bottom)
				(hide yes)
			)
		)
		(pin "1"
		)
		(pin "2"
		)
		(instances
			(project "sodimm-ddr5-tester"
				(path ""
					(reference "C147")
					(unit 1)
				)
			)
		)
	)
	(symbol
		(lib_id "antmicroCapacitors0402:C_10n_0402")
		(at 95.885 51.435 270)
		(unit 1)
		(exclude_from_sim no)
		(in_bom yes)
		(on_board yes)
		(dnp no)
		(property "Reference" "C141"
			(at 96.52 52.07 90)
			(effects
				(font
					(size 1.27 1.27)
				)
				(justify left)
			)
		)
		(property "Value" "C_10n_0402"
			(at 85.725 71.755 0)
			(effects
				(font
					(size 1.27 1.27)
					(thickness 0.15)
				)
				(justify left bottom)
				(hide yes)
			)
		)
		(property "Footprint" "antmicro-footprints:C_0402_1005Metric"
			(at 83.185 71.755 0)
			(effects
				(font
					(size 1.27 1.27)
					(thickness 0.15)
				)
				(justify left bottom)
				(hide yes)
			)
		)
		(property "Datasheet" "https://www.murata.com/products/productdetail?partno=GRM155R71H103KA88%23"
			(at 80.645 71.755 0)
			(effects
				(font
					(size 1.27 1.27)
					(thickness 0.15)
				)
				(justify left bottom)
				(hide yes)
			)
		)
		(property "Description" ""
			(at 95.885 51.435 0)
			(effects
				(font
					(size 1.27 1.27)
				)
			)
		)
		(property "Manufacturer" "Murata"
			(at 75.565 71.755 0)
			(effects
				(font
					(size 1.27 1.27)
					(thickness 0.15)
				)
				(justify left bottom)
				(hide yes)
			)
		)
		(property "MPN" "GRM155R71H103KA88D"
			(at 78.105 71.755 0)
			(effects
				(font
					(size 1.27 1.27)
					(thickness 0.15)
				)
				(justify left bottom)
				(hide yes)
			)
		)
		(property "Val" "10n"
			(at 96.52 55.88 90)
			(effects
				(font
					(size 1.27 1.27)
					(thickness 0.15)
				)
				(justify left)
			)
		)
		(property "License" "Apache-2.0"
			(at 73.025 71.755 0)
			(effects
				(font
					(size 1.27 1.27)
					(thickness 0.15)
				)
				(justify left bottom)
				(hide yes)
			)
		)
		(property "Author" "Antmicro"
			(at 70.485 71.755 0)
			(effects
				(font
					(size 1.27 1.27)
					(thickness 0.15)
				)
				(justify left bottom)
				(hide yes)
			)
		)
		(property "Voltage" "50V"
			(at 67.945 71.755 0)
			(effects
				(font
					(size 1.27 1.27)
				)
				(justify left bottom)
				(hide yes)
			)
		)
		(property "Dielectric" "X7R"
			(at 65.405 71.755 0)
			(effects
				(font
					(size 1.27 1.27)
				)
				(justify left bottom)
				(hide yes)
			)
		)
		(pin "1"
		)
		(pin "2"
		)
		(instances
			(project "sodimm-ddr5-tester"
				(path ""
					(reference "C141")
					(unit 1)
				)
			)
		)
	)
	(symbol
		(lib_id "antmicroCapacitors0402:C_4u7_0402")
		(at 207.01 98.425 270)
		(mirror x)
		(unit 1)
		(exclude_from_sim no)
		(in_bom yes)
		(on_board yes)
		(dnp no)
		(fields_autoplaced yes)
		(property "Reference" "C159"
			(at 207.645 93.98 90)
			(effects
				(font
					(size 1.27 1.27)
				)
				(justify left)
			)
		)
		(property "Value" "C_4u7_0402"
			(at 196.85 78.105 0)
			(effects
				(font
					(size 1.27 1.27)
					(thickness 0.15)
				)
				(justify left bottom)
				(hide yes)
			)
		)
		(property "Footprint" "antmicro-footprints:C_0402_1005Metric"
			(at 194.31 78.105 0)
			(effects
				(font
					(size 1.27 1.27)
					(thickness 0.15)
				)
				(justify left bottom)
				(hide yes)
			)
		)
		(property "Datasheet" "https://www.murata.com/products/productdetail?partno=GRM155R61A475MEAA%23"
			(at 191.77 78.105 0)
			(effects
				(font
					(size 1.27 1.27)
					(thickness 0.15)
				)
				(justify left bottom)
				(hide yes)
			)
		)
		(property "Description" ""
			(at 207.01 98.425 0)
			(effects
				(font
					(size 1.27 1.27)
				)
			)
		)
		(property "Manufacturer" "Murata"
			(at 186.69 78.105 0)
			(effects
				(font
					(size 1.27 1.27)
					(thickness 0.15)
				)
				(justify left bottom)
				(hide yes)
			)
		)
		(property "MPN" "GRM155R61A475MEAAD"
			(at 189.23 78.105 0)
			(effects
				(font
					(size 1.27 1.27)
					(thickness 0.15)
				)
				(justify left bottom)
				(hide yes)
			)
		)
		(property "Val" "4u7"
			(at 207.645 97.79 90)
			(effects
				(font
					(size 1.27 1.27)
					(thickness 0.15)
				)
				(justify left)
			)
		)
		(property "License" "Apache-2.0"
			(at 184.15 78.105 0)
			(effects
				(font
					(size 1.27 1.27)
					(thickness 0.15)
				)
				(justify left bottom)
				(hide yes)
			)
		)
		(property "Author" "Antmicro"
			(at 181.61 78.105 0)
			(effects
				(font
					(size 1.27 1.27)
					(thickness 0.15)
				)
				(justify left bottom)
				(hide yes)
			)
		)
		(property "Voltage" ""
			(at 179.07 78.105 0)
			(effects
				(font
					(size 1.27 1.27)
				)
				(justify left bottom)
				(hide yes)
			)
		)
		(property "Dielectric" ""
			(at 176.53 78.105 0)
			(effects
				(font
					(size 1.27 1.27)
				)
				(justify left bottom)
				(hide yes)
			)
		)
		(pin "1"
		)
		(pin "2"
		)
		(instances
			(project "sodimm-ddr5-tester"
				(path ""
					(reference "C159")
					(unit 1)
				)
			)
		)
	)
	(symbol
		(lib_id "antmicroCapacitors0402:C_10n_0402")
		(at 190.5 98.425 270)
		(mirror x)
		(unit 1)
		(exclude_from_sim no)
		(in_bom yes)
		(on_board yes)
		(dnp no)
		(fields_autoplaced yes)
		(property "Reference" "C154"
			(at 191.135 93.98 90)
			(effects
				(font
					(size 1.27 1.27)
				)
				(justify left)
			)
		)
		(property "Value" "C_10n_0402"
			(at 180.34 78.105 0)
			(effects
				(font
					(size 1.27 1.27)
					(thickness 0.15)
				)
				(justify left bottom)
				(hide yes)
			)
		)
		(property "Footprint" "antmicro-footprints:C_0402_1005Metric"
			(at 177.8 78.105 0)
			(effects
				(font
					(size 1.27 1.27)
					(thickness 0.15)
				)
				(justify left bottom)
				(hide yes)
			)
		)
		(property "Datasheet" "https://www.murata.com/products/productdetail?partno=GRM155R71H103KA88%23"
			(at 175.26 78.105 0)
			(effects
				(font
					(size 1.27 1.27)
					(thickness 0.15)
				)
				(justify left bottom)
				(hide yes)
			)
		)
		(property "Description" ""
			(at 190.5 98.425 0)
			(effects
				(font
					(size 1.27 1.27)
				)
			)
		)
		(property "Manufacturer" "Murata"
			(at 170.18 78.105 0)
			(effects
				(font
					(size 1.27 1.27)
					(thickness 0.15)
				)
				(justify left bottom)
				(hide yes)
			)
		)
		(property "MPN" "GRM155R71H103KA88D"
			(at 172.72 78.105 0)
			(effects
				(font
					(size 1.27 1.27)
					(thickness 0.15)
				)
				(justify left bottom)
				(hide yes)
			)
		)
		(property "Val" "10n"
			(at 191.135 97.79 90)
			(effects
				(font
					(size 1.27 1.27)
					(thickness 0.15)
				)
				(justify left)
			)
		)
		(property "License" "Apache-2.0"
			(at 167.64 78.105 0)
			(effects
				(font
					(size 1.27 1.27)
					(thickness 0.15)
				)
				(justify left bottom)
				(hide yes)
			)
		)
		(property "Author" "Antmicro"
			(at 165.1 78.105 0)
			(effects
				(font
					(size 1.27 1.27)
					(thickness 0.15)
				)
				(justify left bottom)
				(hide yes)
			)
		)
		(property "Voltage" "50V"
			(at 162.56 78.105 0)
			(effects
				(font
					(size 1.27 1.27)
				)
				(justify left bottom)
				(hide yes)
			)
		)
		(property "Dielectric" "X7R"
			(at 160.02 78.105 0)
			(effects
				(font
					(size 1.27 1.27)
				)
				(justify left bottom)
				(hide yes)
			)
		)
		(pin "1"
		)
		(pin "2"
		)
		(instances
			(project "sodimm-ddr5-tester"
				(path ""
					(reference "C154")
					(unit 1)
				)
			)
		)
	)
	(symbol
		(lib_id "antmicropower:GND")
		(at 256.54 62.865 0)
		(mirror y)
		(unit 1)
		(exclude_from_sim no)
		(in_bom yes)
		(on_board yes)
		(dnp no)
		(fields_autoplaced yes)
		(property "Reference" "#PWR0245"
			(at 256.54 69.215 0)
			(effects
				(font
					(size 1.27 1.27)
				)
				(hide yes)
			)
		)
		(property "Value" "GND"
			(at 259.08 64.135 0)
			(effects
				(font
					(size 1.27 1.27)
					(thickness 0.15)
				)
				(justify right)
			)
		)
		(property "Footprint" ""
			(at 247.65 70.485 0)
			(effects
				(font
					(size 1.27 1.27)
					(thickness 0.15)
				)
				(justify left bottom)
				(hide yes)
			)
		)
		(property "Datasheet" ""
			(at 247.65 75.565 0)
			(effects
				(font
					(size 1.27 1.27)
					(thickness 0.15)
				)
				(justify left bottom)
				(hide yes)
			)
		)
		(property "Description" ""
			(at 247.65 78.105 0)
			(effects
				(font
					(size 1.27 1.27)
				)
				(justify left bottom)
				(hide yes)
			)
		)
		(property "Author" "Antmicro"
			(at 247.65 70.485 0)
			(effects
				(font
					(size 1.27 1.27)
					(thickness 0.15)
				)
				(justify left bottom)
				(hide yes)
			)
		)
		(property "License" "Apache-2.0"
			(at 247.65 73.025 0)
			(effects
				(font
					(size 1.27 1.27)
					(thickness 0.15)
				)
				(justify left bottom)
				(hide yes)
			)
		)
		(pin "1"
		)
		(instances
			(project "sodimm-ddr5-tester"
				(path ""
					(reference "#PWR0245")
					(unit 1)
				)
			)
		)
	)
	(symbol
		(lib_id "antmicropower:GND")
		(at 95.885 78.74 0)
		(unit 1)
		(exclude_from_sim no)
		(in_bom yes)
		(on_board yes)
		(dnp no)
		(fields_autoplaced yes)
		(property "Reference" "#PWR0250"
			(at 95.885 85.09 0)
			(effects
				(font
					(size 1.27 1.27)
				)
				(hide yes)
			)
		)
		(property "Value" "GND"
			(at 97.79 80.01 0)
			(effects
				(font
					(size 1.27 1.27)
					(thickness 0.15)
				)
				(justify left)
			)
		)
		(property "Footprint" ""
			(at 104.775 86.36 0)
			(effects
				(font
					(size 1.27 1.27)
					(thickness 0.15)
				)
				(justify left bottom)
				(hide yes)
			)
		)
		(property "Datasheet" ""
			(at 104.775 91.44 0)
			(effects
				(font
					(size 1.27 1.27)
					(thickness 0.15)
				)
				(justify left bottom)
				(hide yes)
			)
		)
		(property "Description" ""
			(at 104.775 93.98 0)
			(effects
				(font
					(size 1.27 1.27)
				)
				(justify left bottom)
				(hide yes)
			)
		)
		(property "Author" "Antmicro"
			(at 104.775 86.36 0)
			(effects
				(font
					(size 1.27 1.27)
					(thickness 0.15)
				)
				(justify left bottom)
				(hide yes)
			)
		)
		(property "License" "Apache-2.0"
			(at 104.775 88.9 0)
			(effects
				(font
					(size 1.27 1.27)
					(thickness 0.15)
				)
				(justify left bottom)
				(hide yes)
			)
		)
		(pin "1"
		)
		(instances
			(project "sodimm-ddr5-tester"
				(path ""
					(reference "#PWR0250")
					(unit 1)
				)
			)
		)
	)
	(symbol
		(lib_id "antmicropower:GND")
		(at 79.375 57.785 0)
		(unit 1)
		(exclude_from_sim no)
		(in_bom yes)
		(on_board yes)
		(dnp no)
		(property "Reference" "#PWR0241"
			(at 79.375 64.135 0)
			(effects
				(font
					(size 1.27 1.27)
				)
				(hide yes)
			)
		)
		(property "Value" "GND"
			(at 77.47 62.23 0)
			(effects
				(font
					(size 1.27 1.27)
					(thickness 0.15)
				)
				(justify left bottom)
			)
		)
		(property "Footprint" ""
			(at 88.265 65.405 0)
			(effects
				(font
					(size 1.27 1.27)
					(thickness 0.15)
				)
				(justify left bottom)
				(hide yes)
			)
		)
		(property "Datasheet" ""
			(at 88.265 70.485 0)
			(effects
				(font
					(size 1.27 1.27)
					(thickness 0.15)
				)
				(justify left bottom)
				(hide yes)
			)
		)
		(property "Description" ""
			(at 88.265 73.025 0)
			(effects
				(font
					(size 1.27 1.27)
				)
				(justify left bottom)
				(hide yes)
			)
		)
		(property "Author" "Antmicro"
			(at 88.265 65.405 0)
			(effects
				(font
					(size 1.27 1.27)
					(thickness 0.15)
				)
				(justify left bottom)
				(hide yes)
			)
		)
		(property "License" "Apache-2.0"
			(at 88.265 67.945 0)
			(effects
				(font
					(size 1.27 1.27)
					(thickness 0.15)
				)
				(justify left bottom)
				(hide yes)
			)
		)
		(pin "1"
		)
		(instances
			(project "sodimm-ddr5-tester"
				(path ""
					(reference "#PWR0241")
					(unit 1)
				)
			)
		)
	)
	(symbol
		(lib_id "antmicropower:GND")
		(at 207.01 99.695 0)
		(unit 1)
		(exclude_from_sim no)
		(in_bom yes)
		(on_board yes)
		(dnp no)
		(fields_autoplaced yes)
		(property "Reference" "#PWR0251"
			(at 207.01 106.045 0)
			(effects
				(font
					(size 1.27 1.27)
				)
				(hide yes)
			)
		)
		(property "Value" "GND"
			(at 209.55 100.965 0)
			(effects
				(font
					(size 1.27 1.27)
					(thickness 0.15)
				)
				(justify left)
			)
		)
		(property "Footprint" ""
			(at 215.9 107.315 0)
			(effects
				(font
					(size 1.27 1.27)
					(thickness 0.15)
				)
				(justify left bottom)
				(hide yes)
			)
		)
		(property "Datasheet" ""
			(at 215.9 112.395 0)
			(effects
				(font
					(size 1.27 1.27)
					(thickness 0.15)
				)
				(justify left bottom)
				(hide yes)
			)
		)
		(property "Description" ""
			(at 215.9 114.935 0)
			(effects
				(font
					(size 1.27 1.27)
				)
				(justify left bottom)
				(hide yes)
			)
		)
		(property "Author" "Antmicro"
			(at 215.9 107.315 0)
			(effects
				(font
					(size 1.27 1.27)
					(thickness 0.15)
				)
				(justify left bottom)
				(hide yes)
			)
		)
		(property "License" "Apache-2.0"
			(at 215.9 109.855 0)
			(effects
				(font
					(size 1.27 1.27)
					(thickness 0.15)
				)
				(justify left bottom)
				(hide yes)
			)
		)
		(pin "1"
		)
		(instances
			(project "sodimm-ddr5-tester"
				(path ""
					(reference "#PWR0251")
					(unit 1)
				)
			)
		)
	)
	(symbol
		(lib_id "antmicropower:GND")
		(at 215.265 83.82 0)
		(unit 1)
		(exclude_from_sim no)
		(in_bom yes)
		(on_board yes)
		(dnp no)
		(fields_autoplaced yes)
		(property "Reference" "#PWR0243"
			(at 215.265 90.17 0)
			(effects
				(font
					(size 1.27 1.27)
				)
				(hide yes)
			)
		)
		(property "Value" "GND"
			(at 217.17 85.09 0)
			(effects
				(font
					(size 1.27 1.27)
					(thickness 0.15)
				)
				(justify left)
			)
		)
		(property "Footprint" ""
			(at 224.155 91.44 0)
			(effects
				(font
					(size 1.27 1.27)
					(thickness 0.15)
				)
				(justify left bottom)
				(hide yes)
			)
		)
		(property "Datasheet" ""
			(at 224.155 96.52 0)
			(effects
				(font
					(size 1.27 1.27)
					(thickness 0.15)
				)
				(justify left bottom)
				(hide yes)
			)
		)
		(property "Description" ""
			(at 224.155 99.06 0)
			(effects
				(font
					(size 1.27 1.27)
				)
				(justify left bottom)
				(hide yes)
			)
		)
		(property "Author" "Antmicro"
			(at 224.155 91.44 0)
			(effects
				(font
					(size 1.27 1.27)
					(thickness 0.15)
				)
				(justify left bottom)
				(hide yes)
			)
		)
		(property "License" "Apache-2.0"
			(at 224.155 93.98 0)
			(effects
				(font
					(size 1.27 1.27)
					(thickness 0.15)
				)
				(justify left bottom)
				(hide yes)
			)
		)
		(pin "1"
		)
		(instances
			(project "sodimm-ddr5-tester"
				(path ""
					(reference "#PWR0243")
					(unit 1)
				)
			)
		)
	)
	(symbol
		(lib_id "antmicropower:GND")
		(at 273.05 140.97 0)
		(unit 1)
		(exclude_from_sim no)
		(in_bom yes)
		(on_board yes)
		(dnp no)
		(property "Reference" "#PWR0242"
			(at 273.05 147.32 0)
			(effects
				(font
					(size 1.27 1.27)
				)
				(hide yes)
			)
		)
		(property "Value" "GND"
			(at 271.018 145.034 0)
			(effects
				(font
					(size 1.27 1.27)
					(thickness 0.15)
				)
				(justify left)
			)
		)
		(property "Footprint" ""
			(at 281.94 148.59 0)
			(effects
				(font
					(size 1.27 1.27)
					(thickness 0.15)
				)
				(justify left bottom)
				(hide yes)
			)
		)
		(property "Datasheet" ""
			(at 281.94 153.67 0)
			(effects
				(font
					(size 1.27 1.27)
					(thickness 0.15)
				)
				(justify left bottom)
				(hide yes)
			)
		)
		(property "Description" ""
			(at 281.94 156.21 0)
			(effects
				(font
					(size 1.27 1.27)
				)
				(justify left bottom)
				(hide yes)
			)
		)
		(property "Author" "Antmicro"
			(at 281.94 148.59 0)
			(effects
				(font
					(size 1.27 1.27)
					(thickness 0.15)
				)
				(justify left bottom)
				(hide yes)
			)
		)
		(property "License" "Apache-2.0"
			(at 281.94 151.13 0)
			(effects
				(font
					(size 1.27 1.27)
					(thickness 0.15)
				)
				(justify left bottom)
				(hide yes)
			)
		)
		(pin "1"
		)
		(instances
			(project "sodimm-ddr5-tester"
				(path ""
					(reference "#PWR0242")
					(unit 1)
				)
			)
		)
	)
	(symbol
		(lib_id "antmicroResistors0402:R_220R_0402")
		(at 316.23 114.3 0)
		(mirror x)
		(unit 1)
		(exclude_from_sim no)
		(in_bom yes)
		(on_board yes)
		(dnp no)
		(property "Reference" "R98"
			(at 314.706 113.284 0)
			(effects
				(font
					(size 1.27 1.27)
				)
			)
		)
		(property "Value" "R_220R_0402"
			(at 336.55 101.6 0)
			(effects
				(font
					(size 1.27 1.27)
					(thickness 0.15)
				)
				(justify left bottom)
				(hide yes)
			)
		)
		(property "Footprint" "antmicro-footprints:R_0402_1005Metric"
			(at 336.55 99.06 0)
			(effects
				(font
					(size 1.27 1.27)
					(thickness 0.15)
				)
				(justify left bottom)
				(hide yes)
			)
		)
		(property "Datasheet" "https://www.bourns.com/docs/product-datasheets/cr.pdf"
			(at 336.55 96.52 0)
			(effects
				(font
					(size 1.27 1.27)
					(thickness 0.15)
				)
				(justify left bottom)
				(hide yes)
			)
		)
		(property "Description" ""
			(at 316.23 114.3 0)
			(effects
				(font
					(size 1.27 1.27)
				)
			)
		)
		(property "Manufacturer" "Bourns"
			(at 336.55 91.44 0)
			(effects
				(font
					(size 1.27 1.27)
					(thickness 0.15)
				)
				(justify left bottom)
				(hide yes)
			)
		)
		(property "MPN" "CR0402-FX-2200GLF"
			(at 336.55 93.98 0)
			(effects
				(font
					(size 1.27 1.27)
					(thickness 0.15)
				)
				(justify left bottom)
				(hide yes)
			)
		)
		(property "Val" "220R"
			(at 323.342 113.284 0)
			(effects
				(font
					(size 1.27 1.27)
					(thickness 0.15)
				)
			)
		)
		(property "License" "Apache-2.0"
			(at 336.55 88.9 0)
			(effects
				(font
					(size 1.27 1.27)
					(thickness 0.15)
				)
				(justify left bottom)
				(hide yes)
			)
		)
		(property "Author" "Antmicro"
			(at 336.55 86.36 0)
			(effects
				(font
					(size 1.27 1.27)
					(thickness 0.15)
				)
				(justify left bottom)
				(hide yes)
			)
		)
		(property "Tolerance" "1%"
			(at 336.55 104.14 0)
			(effects
				(font
					(size 1.27 1.27)
				)
				(justify left bottom)
				(hide yes)
			)
		)
		(pin "1"
		)
		(pin "2"
		)
		(instances
			(project "sodimm-ddr5-tester"
				(path ""
					(reference "R98")
					(unit 1)
				)
			)
		)
	)
	(symbol
		(lib_id "antmicroResistors0402:R_220R_0402")
		(at 316.23 139.7 0)
		(mirror x)
		(unit 1)
		(exclude_from_sim no)
		(in_bom yes)
		(on_board yes)
		(dnp no)
		(property "Reference" "R99"
			(at 314.706 138.684 0)
			(effects
				(font
					(size 1.27 1.27)
				)
			)
		)
		(property "Value" "R_220R_0402"
			(at 336.55 127 0)
			(effects
				(font
					(size 1.27 1.27)
					(thickness 0.15)
				)
				(justify left bottom)
				(hide yes)
			)
		)
		(property "Footprint" "antmicro-footprints:R_0402_1005Metric"
			(at 336.55 124.46 0)
			(effects
				(font
					(size 1.27 1.27)
					(thickness 0.15)
				)
				(justify left bottom)
				(hide yes)
			)
		)
		(property "Datasheet" "https://www.bourns.com/docs/product-datasheets/cr.pdf"
			(at 336.55 121.92 0)
			(effects
				(font
					(size 1.27 1.27)
					(thickness 0.15)
				)
				(justify left bottom)
				(hide yes)
			)
		)
		(property "Description" ""
			(at 316.23 139.7 0)
			(effects
				(font
					(size 1.27 1.27)
				)
			)
		)
		(property "Manufacturer" "Bourns"
			(at 336.55 116.84 0)
			(effects
				(font
					(size 1.27 1.27)
					(thickness 0.15)
				)
				(justify left bottom)
				(hide yes)
			)
		)
		(property "MPN" "CR0402-FX-2200GLF"
			(at 336.55 119.38 0)
			(effects
				(font
					(size 1.27 1.27)
					(thickness 0.15)
				)
				(justify left bottom)
				(hide yes)
			)
		)
		(property "Val" "220R"
			(at 323.596 138.43 0)
			(effects
				(font
					(size 1.27 1.27)
					(thickness 0.15)
				)
			)
		)
		(property "License" "Apache-2.0"
			(at 336.55 114.3 0)
			(effects
				(font
					(size 1.27 1.27)
					(thickness 0.15)
				)
				(justify left bottom)
				(hide yes)
			)
		)
		(property "Author" "Antmicro"
			(at 336.55 111.76 0)
			(effects
				(font
					(size 1.27 1.27)
					(thickness 0.15)
				)
				(justify left bottom)
				(hide yes)
			)
		)
		(property "Tolerance" "1%"
			(at 336.55 129.54 0)
			(effects
				(font
					(size 1.27 1.27)
				)
				(justify left bottom)
				(hide yes)
			)
		)
		(pin "1"
		)
		(pin "2"
		)
		(instances
			(project "sodimm-ddr5-tester"
				(path ""
					(reference "R99")
					(unit 1)
				)
			)
		)
	)
	(symbol
		(lib_id "antmicroResistors0402:R_1k_0402")
		(at 97.155 101.6 180)
		(unit 1)
		(exclude_from_sim no)
		(in_bom yes)
		(on_board yes)
		(dnp no)
		(property "Reference" "R110"
			(at 100.965 102.87 0)
			(effects
				(font
					(size 1.27 1.27)
				)
			)
		)
		(property "Value" "R_1k_0402"
			(at 76.835 88.9 0)
			(effects
				(font
					(size 1.27 1.27)
					(thickness 0.15)
				)
				(justify left bottom)
				(hide yes)
			)
		)
		(property "Footprint" "antmicro-footprints:R_0402_1005Metric"
			(at 76.835 86.36 0)
			(effects
				(font
					(size 1.27 1.27)
					(thickness 0.15)
				)
				(justify left bottom)
				(hide yes)
			)
		)
		(property "Datasheet" "https://www.bourns.com/docs/product-datasheets/cr.pdf"
			(at 76.835 83.82 0)
			(effects
				(font
					(size 1.27 1.27)
					(thickness 0.15)
				)
				(justify left bottom)
				(hide yes)
			)
		)
		(property "Description" ""
			(at 97.155 101.6 0)
			(effects
				(font
					(size 1.27 1.27)
				)
			)
		)
		(property "Manufacturer" "Bourns"
			(at 76.835 78.74 0)
			(effects
				(font
					(size 1.27 1.27)
					(thickness 0.15)
				)
				(justify left bottom)
				(hide yes)
			)
		)
		(property "MPN" "CR0402-FX-1001GLF"
			(at 76.835 81.28 0)
			(effects
				(font
					(size 1.27 1.27)
					(thickness 0.15)
				)
				(justify left bottom)
				(hide yes)
			)
		)
		(property "Val" "1k"
			(at 90.17 102.87 0)
			(effects
				(font
					(size 1.27 1.27)
					(thickness 0.15)
				)
			)
		)
		(property "License" "Apache-2.0"
			(at 76.835 76.2 0)
			(effects
				(font
					(size 1.27 1.27)
					(thickness 0.15)
				)
				(justify left bottom)
				(hide yes)
			)
		)
		(property "Author" "Antmicro"
			(at 76.835 73.66 0)
			(effects
				(font
					(size 1.27 1.27)
					(thickness 0.15)
				)
				(justify left bottom)
				(hide yes)
			)
		)
		(property "Tolerance" "1%"
			(at 76.835 91.44 0)
			(effects
				(font
					(size 1.27 1.27)
				)
				(justify left bottom)
				(hide yes)
			)
		)
		(pin "1"
		)
		(pin "2"
		)
		(instances
			(project "sodimm-ddr5-tester"
				(path ""
					(reference "R110")
					(unit 1)
				)
			)
		)
	)
	(symbol
		(lib_id "antmicroResistors0402:R_2k2_0402")
		(at 100.965 213.995 0)
		(unit 1)
		(exclude_from_sim no)
		(in_bom yes)
		(on_board yes)
		(dnp no)
		(property "Reference" "R113"
			(at 97.79 212.725 0)
			(effects
				(font
					(size 1.27 1.27)
				)
			)
		)
		(property "Value" "R_2k2_0402"
			(at 121.285 226.695 0)
			(effects
				(font
					(size 1.27 1.27)
					(thickness 0.15)
				)
				(justify left bottom)
				(hide yes)
			)
		)
		(property "Footprint" "antmicro-footprints:R_0402_1005Metric"
			(at 121.285 229.235 0)
			(effects
				(font
					(size 1.27 1.27)
					(thickness 0.15)
				)
				(justify left bottom)
				(hide yes)
			)
		)
		(property "Datasheet" "https://www.bourns.com/docs/product-datasheets/cr.pdf"
			(at 121.285 231.775 0)
			(effects
				(font
					(size 1.27 1.27)
					(thickness 0.15)
				)
				(justify left bottom)
				(hide yes)
			)
		)
		(property "Description" ""
			(at 100.965 213.995 0)
			(effects
				(font
					(size 1.27 1.27)
				)
			)
		)
		(property "Manufacturer" "Bourns"
			(at 121.285 236.855 0)
			(effects
				(font
					(size 1.27 1.27)
					(thickness 0.15)
				)
				(justify left bottom)
				(hide yes)
			)
		)
		(property "MPN" "CR0402-FX-2201GLF"
			(at 121.285 234.315 0)
			(effects
				(font
					(size 1.27 1.27)
					(thickness 0.15)
				)
				(justify left bottom)
				(hide yes)
			)
		)
		(property "Val" "2k2"
			(at 107.315 212.725 0)
			(effects
				(font
					(size 1.27 1.27)
					(thickness 0.15)
				)
			)
		)
		(property "License" "Apache-2.0"
			(at 121.285 239.395 0)
			(effects
				(font
					(size 1.27 1.27)
					(thickness 0.15)
				)
				(justify left bottom)
				(hide yes)
			)
		)
		(property "Author" "Antmicro"
			(at 121.285 241.935 0)
			(effects
				(font
					(size 1.27 1.27)
					(thickness 0.15)
				)
				(justify left bottom)
				(hide yes)
			)
		)
		(property "Tolerance" "1%"
			(at 121.285 224.155 0)
			(effects
				(font
					(size 1.27 1.27)
				)
				(justify left bottom)
				(hide yes)
			)
		)
		(pin "1"
		)
		(pin "2"
		)
		(instances
			(project "sodimm-ddr5-tester"
				(path ""
					(reference "R113")
					(unit 1)
				)
			)
		)
	)
	(symbol
		(lib_id "antmicroResistors0402:R_2k2_0402")
		(at 100.965 211.455 0)
		(unit 1)
		(exclude_from_sim no)
		(in_bom yes)
		(on_board yes)
		(dnp no)
		(property "Reference" "R114"
			(at 97.79 210.185 0)
			(effects
				(font
					(size 1.27 1.27)
				)
			)
		)
		(property "Value" "R_2k2_0402"
			(at 121.285 224.155 0)
			(effects
				(font
					(size 1.27 1.27)
					(thickness 0.15)
				)
				(justify left bottom)
				(hide yes)
			)
		)
		(property "Footprint" "antmicro-footprints:R_0402_1005Metric"
			(at 121.285 226.695 0)
			(effects
				(font
					(size 1.27 1.27)
					(thickness 0.15)
				)
				(justify left bottom)
				(hide yes)
			)
		)
		(property "Datasheet" "https://www.bourns.com/docs/product-datasheets/cr.pdf"
			(at 121.285 229.235 0)
			(effects
				(font
					(size 1.27 1.27)
					(thickness 0.15)
				)
				(justify left bottom)
				(hide yes)
			)
		)
		(property "Description" ""
			(at 100.965 211.455 0)
			(effects
				(font
					(size 1.27 1.27)
				)
			)
		)
		(property "Manufacturer" "Bourns"
			(at 121.285 234.315 0)
			(effects
				(font
					(size 1.27 1.27)
					(thickness 0.15)
				)
				(justify left bottom)
				(hide yes)
			)
		)
		(property "MPN" "CR0402-FX-2201GLF"
			(at 121.285 231.775 0)
			(effects
				(font
					(size 1.27 1.27)
					(thickness 0.15)
				)
				(justify left bottom)
				(hide yes)
			)
		)
		(property "Val" "2k2"
			(at 107.315 210.185 0)
			(effects
				(font
					(size 1.27 1.27)
					(thickness 0.15)
				)
			)
		)
		(property "License" "Apache-2.0"
			(at 121.285 236.855 0)
			(effects
				(font
					(size 1.27 1.27)
					(thickness 0.15)
				)
				(justify left bottom)
				(hide yes)
			)
		)
		(property "Author" "Antmicro"
			(at 121.285 239.395 0)
			(effects
				(font
					(size 1.27 1.27)
					(thickness 0.15)
				)
				(justify left bottom)
				(hide yes)
			)
		)
		(property "Tolerance" "1%"
			(at 121.285 221.615 0)
			(effects
				(font
					(size 1.27 1.27)
				)
				(justify left bottom)
				(hide yes)
			)
		)
		(pin "1"
		)
		(pin "2"
		)
		(instances
			(project "sodimm-ddr5-tester"
				(path ""
					(reference "R114")
					(unit 1)
				)
			)
		)
	)
	(symbol
		(lib_id "antmicroResistors0402:R_2k2_0402")
		(at 100.965 208.915 0)
		(unit 1)
		(exclude_from_sim no)
		(in_bom no)
		(on_board yes)
		(dnp yes)
		(property "Reference" "R115"
			(at 97.79 207.645 0)
			(effects
				(font
					(size 1.27 1.27)
				)
			)
		)
		(property "Value" "R_2k2_0402"
			(at 121.285 221.615 0)
			(effects
				(font
					(size 1.27 1.27)
					(thickness 0.15)
				)
				(justify left bottom)
				(hide yes)
			)
		)
		(property "Footprint" "antmicro-footprints:R_0402_1005Metric"
			(at 121.285 224.155 0)
			(effects
				(font
					(size 1.27 1.27)
					(thickness 0.15)
				)
				(justify left bottom)
				(hide yes)
			)
		)
		(property "Datasheet" "https://www.bourns.com/docs/product-datasheets/cr.pdf"
			(at 121.285 226.695 0)
			(effects
				(font
					(size 1.27 1.27)
					(thickness 0.15)
				)
				(justify left bottom)
				(hide yes)
			)
		)
		(property "Description" ""
			(at 100.965 208.915 0)
			(effects
				(font
					(size 1.27 1.27)
				)
			)
		)
		(property "Manufacturer" "Bourns"
			(at 121.285 231.775 0)
			(effects
				(font
					(size 1.27 1.27)
					(thickness 0.15)
				)
				(justify left bottom)
				(hide yes)
			)
		)
		(property "MPN" "CR0402-FX-2201GLF"
			(at 121.285 229.235 0)
			(effects
				(font
					(size 1.27 1.27)
					(thickness 0.15)
				)
				(justify left bottom)
				(hide yes)
			)
		)
		(property "Val" "2k2"
			(at 107.315 207.645 0)
			(effects
				(font
					(size 1.27 1.27)
					(thickness 0.15)
				)
			)
		)
		(property "License" "Apache-2.0"
			(at 121.285 234.315 0)
			(effects
				(font
					(size 1.27 1.27)
					(thickness 0.15)
				)
				(justify left bottom)
				(hide yes)
			)
		)
		(property "Author" "Antmicro"
			(at 121.285 236.855 0)
			(effects
				(font
					(size 1.27 1.27)
					(thickness 0.15)
				)
				(justify left bottom)
				(hide yes)
			)
		)
		(property "Tolerance" "1%"
			(at 121.285 219.075 0)
			(effects
				(font
					(size 1.27 1.27)
				)
				(justify left bottom)
				(hide yes)
			)
		)
		(pin "1"
		)
		(pin "2"
		)
		(instances
			(project "sodimm-ddr5-tester"
				(path ""
					(reference "R115")
					(unit 1)
				)
			)
		)
	)
	(symbol
		(lib_id "antmicroResistors0402:R_2k2_0402")
		(at 100.965 206.375 0)
		(unit 1)
		(exclude_from_sim no)
		(in_bom no)
		(on_board yes)
		(dnp yes)
		(property "Reference" "R116"
			(at 97.79 205.105 0)
			(effects
				(font
					(size 1.27 1.27)
				)
			)
		)
		(property "Value" "R_2k2_0402"
			(at 121.285 219.075 0)
			(effects
				(font
					(size 1.27 1.27)
					(thickness 0.15)
				)
				(justify left bottom)
				(hide yes)
			)
		)
		(property "Footprint" "antmicro-footprints:R_0402_1005Metric"
			(at 121.285 221.615 0)
			(effects
				(font
					(size 1.27 1.27)
					(thickness 0.15)
				)
				(justify left bottom)
				(hide yes)
			)
		)
		(property "Datasheet" "https://www.bourns.com/docs/product-datasheets/cr.pdf"
			(at 121.285 224.155 0)
			(effects
				(font
					(size 1.27 1.27)
					(thickness 0.15)
				)
				(justify left bottom)
				(hide yes)
			)
		)
		(property "Description" ""
			(at 100.965 206.375 0)
			(effects
				(font
					(size 1.27 1.27)
				)
			)
		)
		(property "Manufacturer" "Bourns"
			(at 121.285 229.235 0)
			(effects
				(font
					(size 1.27 1.27)
					(thickness 0.15)
				)
				(justify left bottom)
				(hide yes)
			)
		)
		(property "MPN" "CR0402-FX-2201GLF"
			(at 121.285 226.695 0)
			(effects
				(font
					(size 1.27 1.27)
					(thickness 0.15)
				)
				(justify left bottom)
				(hide yes)
			)
		)
		(property "Val" "2k2"
			(at 107.315 205.105 0)
			(effects
				(font
					(size 1.27 1.27)
					(thickness 0.15)
				)
			)
		)
		(property "License" "Apache-2.0"
			(at 121.285 231.775 0)
			(effects
				(font
					(size 1.27 1.27)
					(thickness 0.15)
				)
				(justify left bottom)
				(hide yes)
			)
		)
		(property "Author" "Antmicro"
			(at 121.285 234.315 0)
			(effects
				(font
					(size 1.27 1.27)
					(thickness 0.15)
				)
				(justify left bottom)
				(hide yes)
			)
		)
		(property "Tolerance" "1%"
			(at 121.285 216.535 0)
			(effects
				(font
					(size 1.27 1.27)
				)
				(justify left bottom)
				(hide yes)
			)
		)
		(pin "1"
		)
		(pin "2"
		)
		(instances
			(project "sodimm-ddr5-tester"
				(path ""
					(reference "R116")
					(unit 1)
				)
			)
		)
	)
	(symbol
		(lib_id "antmicroResistors0402:R_2k2_0402")
		(at 100.965 225.425 0)
		(unit 1)
		(exclude_from_sim no)
		(in_bom yes)
		(on_board yes)
		(dnp no)
		(property "Reference" "R117"
			(at 97.79 224.155 0)
			(effects
				(font
					(size 1.27 1.27)
				)
			)
		)
		(property "Value" "R_2k2_0402"
			(at 121.285 238.125 0)
			(effects
				(font
					(size 1.27 1.27)
					(thickness 0.15)
				)
				(justify left bottom)
				(hide yes)
			)
		)
		(property "Footprint" "antmicro-footprints:R_0402_1005Metric"
			(at 121.285 240.665 0)
			(effects
				(font
					(size 1.27 1.27)
					(thickness 0.15)
				)
				(justify left bottom)
				(hide yes)
			)
		)
		(property "Datasheet" "https://www.bourns.com/docs/product-datasheets/cr.pdf"
			(at 121.285 243.205 0)
			(effects
				(font
					(size 1.27 1.27)
					(thickness 0.15)
				)
				(justify left bottom)
				(hide yes)
			)
		)
		(property "Description" ""
			(at 100.965 225.425 0)
			(effects
				(font
					(size 1.27 1.27)
				)
			)
		)
		(property "Manufacturer" "Bourns"
			(at 121.285 248.285 0)
			(effects
				(font
					(size 1.27 1.27)
					(thickness 0.15)
				)
				(justify left bottom)
				(hide yes)
			)
		)
		(property "MPN" "CR0402-FX-2201GLF"
			(at 121.285 245.745 0)
			(effects
				(font
					(size 1.27 1.27)
					(thickness 0.15)
				)
				(justify left bottom)
				(hide yes)
			)
		)
		(property "Val" "2k2"
			(at 107.315 224.155 0)
			(effects
				(font
					(size 1.27 1.27)
					(thickness 0.15)
				)
			)
		)
		(property "License" "Apache-2.0"
			(at 121.285 250.825 0)
			(effects
				(font
					(size 1.27 1.27)
					(thickness 0.15)
				)
				(justify left bottom)
				(hide yes)
			)
		)
		(property "Author" "Antmicro"
			(at 121.285 253.365 0)
			(effects
				(font
					(size 1.27 1.27)
					(thickness 0.15)
				)
				(justify left bottom)
				(hide yes)
			)
		)
		(property "Tolerance" "1%"
			(at 121.285 235.585 0)
			(effects
				(font
					(size 1.27 1.27)
				)
				(justify left bottom)
				(hide yes)
			)
		)
		(pin "1"
		)
		(pin "2"
		)
		(instances
			(project "sodimm-ddr5-tester"
				(path ""
					(reference "R117")
					(unit 1)
				)
			)
		)
	)
	(symbol
		(lib_id "antmicroResistors0402:R_2k2_0402")
		(at 100.965 217.17 0)
		(unit 1)
		(exclude_from_sim no)
		(in_bom yes)
		(on_board yes)
		(dnp no)
		(property "Reference" "R118"
			(at 97.79 215.9 0)
			(effects
				(font
					(size 1.27 1.27)
				)
			)
		)
		(property "Value" "R_2k2_0402"
			(at 121.285 229.87 0)
			(effects
				(font
					(size 1.27 1.27)
					(thickness 0.15)
				)
				(justify left bottom)
				(hide yes)
			)
		)
		(property "Footprint" "antmicro-footprints:R_0402_1005Metric"
			(at 121.285 232.41 0)
			(effects
				(font
					(size 1.27 1.27)
					(thickness 0.15)
				)
				(justify left bottom)
				(hide yes)
			)
		)
		(property "Datasheet" "https://www.bourns.com/docs/product-datasheets/cr.pdf"
			(at 121.285 234.95 0)
			(effects
				(font
					(size 1.27 1.27)
					(thickness 0.15)
				)
				(justify left bottom)
				(hide yes)
			)
		)
		(property "Description" ""
			(at 100.965 217.17 0)
			(effects
				(font
					(size 1.27 1.27)
				)
			)
		)
		(property "Manufacturer" "Bourns"
			(at 121.285 240.03 0)
			(effects
				(font
					(size 1.27 1.27)
					(thickness 0.15)
				)
				(justify left bottom)
				(hide yes)
			)
		)
		(property "MPN" "CR0402-FX-2201GLF"
			(at 121.285 237.49 0)
			(effects
				(font
					(size 1.27 1.27)
					(thickness 0.15)
				)
				(justify left bottom)
				(hide yes)
			)
		)
		(property "Val" "2k2"
			(at 107.315 215.9 0)
			(effects
				(font
					(size 1.27 1.27)
					(thickness 0.15)
				)
			)
		)
		(property "License" "Apache-2.0"
			(at 121.285 242.57 0)
			(effects
				(font
					(size 1.27 1.27)
					(thickness 0.15)
				)
				(justify left bottom)
				(hide yes)
			)
		)
		(property "Author" "Antmicro"
			(at 121.285 245.11 0)
			(effects
				(font
					(size 1.27 1.27)
					(thickness 0.15)
				)
				(justify left bottom)
				(hide yes)
			)
		)
		(property "Tolerance" "1%"
			(at 121.285 227.33 0)
			(effects
				(font
					(size 1.27 1.27)
				)
				(justify left bottom)
				(hide yes)
			)
		)
		(pin "1"
		)
		(pin "2"
		)
		(instances
			(project "sodimm-ddr5-tester"
				(path ""
					(reference "R118")
					(unit 1)
				)
			)
		)
	)
	(symbol
		(lib_id "antmicroResistors0402:R_2k2_0402")
		(at 100.965 219.71 0)
		(unit 1)
		(exclude_from_sim no)
		(in_bom no)
		(on_board yes)
		(dnp yes)
		(property "Reference" "R120"
			(at 97.79 218.44 0)
			(effects
				(font
					(size 1.27 1.27)
				)
			)
		)
		(property "Value" "R_2k2_0402"
			(at 121.285 232.41 0)
			(effects
				(font
					(size 1.27 1.27)
					(thickness 0.15)
				)
				(justify left bottom)
				(hide yes)
			)
		)
		(property "Footprint" "antmicro-footprints:R_0402_1005Metric"
			(at 121.285 234.95 0)
			(effects
				(font
					(size 1.27 1.27)
					(thickness 0.15)
				)
				(justify left bottom)
				(hide yes)
			)
		)
		(property "Datasheet" "https://www.bourns.com/docs/product-datasheets/cr.pdf"
			(at 121.285 237.49 0)
			(effects
				(font
					(size 1.27 1.27)
					(thickness 0.15)
				)
				(justify left bottom)
				(hide yes)
			)
		)
		(property "Description" ""
			(at 100.965 219.71 0)
			(effects
				(font
					(size 1.27 1.27)
				)
			)
		)
		(property "Manufacturer" "Bourns"
			(at 121.285 242.57 0)
			(effects
				(font
					(size 1.27 1.27)
					(thickness 0.15)
				)
				(justify left bottom)
				(hide yes)
			)
		)
		(property "MPN" "CR0402-FX-2201GLF"
			(at 121.285 240.03 0)
			(effects
				(font
					(size 1.27 1.27)
					(thickness 0.15)
				)
				(justify left bottom)
				(hide yes)
			)
		)
		(property "Val" "2k2"
			(at 107.315 218.44 0)
			(effects
				(font
					(size 1.27 1.27)
					(thickness 0.15)
				)
			)
		)
		(property "License" "Apache-2.0"
			(at 121.285 245.11 0)
			(effects
				(font
					(size 1.27 1.27)
					(thickness 0.15)
				)
				(justify left bottom)
				(hide yes)
			)
		)
		(property "Author" "Antmicro"
			(at 121.285 247.65 0)
			(effects
				(font
					(size 1.27 1.27)
					(thickness 0.15)
				)
				(justify left bottom)
				(hide yes)
			)
		)
		(property "Tolerance" "1%"
			(at 121.285 229.87 0)
			(effects
				(font
					(size 1.27 1.27)
				)
				(justify left bottom)
				(hide yes)
			)
		)
		(pin "1"
		)
		(pin "2"
		)
		(instances
			(project "sodimm-ddr5-tester"
				(path ""
					(reference "R120")
					(unit 1)
				)
			)
		)
	)
	(symbol
		(lib_id "antmicroResistors0402:R_2k2_0402")
		(at 100.965 222.25 0)
		(unit 1)
		(exclude_from_sim no)
		(in_bom no)
		(on_board yes)
		(dnp yes)
		(property "Reference" "R121"
			(at 97.79 220.98 0)
			(effects
				(font
					(size 1.27 1.27)
				)
			)
		)
		(property "Value" "R_2k2_0402"
			(at 121.285 234.95 0)
			(effects
				(font
					(size 1.27 1.27)
					(thickness 0.15)
				)
				(justify left bottom)
				(hide yes)
			)
		)
		(property "Footprint" "antmicro-footprints:R_0402_1005Metric"
			(at 121.285 237.49 0)
			(effects
				(font
					(size 1.27 1.27)
					(thickness 0.15)
				)
				(justify left bottom)
				(hide yes)
			)
		)
		(property "Datasheet" "https://www.bourns.com/docs/product-datasheets/cr.pdf"
			(at 121.285 240.03 0)
			(effects
				(font
					(size 1.27 1.27)
					(thickness 0.15)
				)
				(justify left bottom)
				(hide yes)
			)
		)
		(property "Description" ""
			(at 100.965 222.25 0)
			(effects
				(font
					(size 1.27 1.27)
				)
			)
		)
		(property "Manufacturer" "Bourns"
			(at 121.285 245.11 0)
			(effects
				(font
					(size 1.27 1.27)
					(thickness 0.15)
				)
				(justify left bottom)
				(hide yes)
			)
		)
		(property "MPN" "CR0402-FX-2201GLF"
			(at 121.285 242.57 0)
			(effects
				(font
					(size 1.27 1.27)
					(thickness 0.15)
				)
				(justify left bottom)
				(hide yes)
			)
		)
		(property "Val" "2k2"
			(at 107.315 220.98 0)
			(effects
				(font
					(size 1.27 1.27)
					(thickness 0.15)
				)
			)
		)
		(property "License" "Apache-2.0"
			(at 121.285 247.65 0)
			(effects
				(font
					(size 1.27 1.27)
					(thickness 0.15)
				)
				(justify left bottom)
				(hide yes)
			)
		)
		(property "Author" "Antmicro"
			(at 121.285 250.19 0)
			(effects
				(font
					(size 1.27 1.27)
					(thickness 0.15)
				)
				(justify left bottom)
				(hide yes)
			)
		)
		(property "Tolerance" "1%"
			(at 121.285 232.41 0)
			(effects
				(font
					(size 1.27 1.27)
				)
				(justify left bottom)
				(hide yes)
			)
		)
		(pin "1"
		)
		(pin "2"
		)
		(instances
			(project "sodimm-ddr5-tester"
				(path ""
					(reference "R121")
					(unit 1)
				)
			)
		)
	)
	(symbol
		(lib_id "antmicroResistors0402:R_2k2_0402")
		(at 100.965 227.965 0)
		(unit 1)
		(exclude_from_sim no)
		(in_bom no)
		(on_board yes)
		(dnp yes)
		(property "Reference" "R119"
			(at 97.79 226.695 0)
			(effects
				(font
					(size 1.27 1.27)
				)
			)
		)
		(property "Value" "R_2k2_0402"
			(at 121.285 240.665 0)
			(effects
				(font
					(size 1.27 1.27)
					(thickness 0.15)
				)
				(justify left bottom)
				(hide yes)
			)
		)
		(property "Footprint" "antmicro-footprints:R_0402_1005Metric"
			(at 121.285 243.205 0)
			(effects
				(font
					(size 1.27 1.27)
					(thickness 0.15)
				)
				(justify left bottom)
				(hide yes)
			)
		)
		(property "Datasheet" "https://www.bourns.com/docs/product-datasheets/cr.pdf"
			(at 121.285 245.745 0)
			(effects
				(font
					(size 1.27 1.27)
					(thickness 0.15)
				)
				(justify left bottom)
				(hide yes)
			)
		)
		(property "Description" ""
			(at 100.965 227.965 0)
			(effects
				(font
					(size 1.27 1.27)
				)
			)
		)
		(property "Manufacturer" "Bourns"
			(at 121.285 250.825 0)
			(effects
				(font
					(size 1.27 1.27)
					(thickness 0.15)
				)
				(justify left bottom)
				(hide yes)
			)
		)
		(property "MPN" "CR0402-FX-2201GLF"
			(at 121.285 248.285 0)
			(effects
				(font
					(size 1.27 1.27)
					(thickness 0.15)
				)
				(justify left bottom)
				(hide yes)
			)
		)
		(property "Val" "2k2"
			(at 107.315 226.695 0)
			(effects
				(font
					(size 1.27 1.27)
					(thickness 0.15)
				)
			)
		)
		(property "License" "Apache-2.0"
			(at 121.285 253.365 0)
			(effects
				(font
					(size 1.27 1.27)
					(thickness 0.15)
				)
				(justify left bottom)
				(hide yes)
			)
		)
		(property "Author" "Antmicro"
			(at 121.285 255.905 0)
			(effects
				(font
					(size 1.27 1.27)
					(thickness 0.15)
				)
				(justify left bottom)
				(hide yes)
			)
		)
		(property "Tolerance" "1%"
			(at 121.285 238.125 0)
			(effects
				(font
					(size 1.27 1.27)
				)
				(justify left bottom)
				(hide yes)
			)
		)
		(pin "1"
		)
		(pin "2"
		)
		(instances
			(project "sodimm-ddr5-tester"
				(path ""
					(reference "R119")
					(unit 1)
				)
			)
		)
	)
	(symbol
		(lib_id "antmicropower:GND")
		(at 116.84 229.235 0)
		(unit 1)
		(exclude_from_sim no)
		(in_bom yes)
		(on_board yes)
		(dnp no)
		(property "Reference" "#PWR0261"
			(at 116.84 235.585 0)
			(effects
				(font
					(size 1.27 1.27)
				)
				(hide yes)
			)
		)
		(property "Value" "GND"
			(at 114.935 233.68 0)
			(effects
				(font
					(size 1.27 1.27)
					(thickness 0.15)
				)
				(justify left bottom)
			)
		)
		(property "Footprint" ""
			(at 125.73 236.855 0)
			(effects
				(font
					(size 1.27 1.27)
					(thickness 0.15)
				)
				(justify left bottom)
				(hide yes)
			)
		)
		(property "Datasheet" ""
			(at 125.73 241.935 0)
			(effects
				(font
					(size 1.27 1.27)
					(thickness 0.15)
				)
				(justify left bottom)
				(hide yes)
			)
		)
		(property "Description" ""
			(at 125.73 244.475 0)
			(effects
				(font
					(size 1.27 1.27)
				)
				(justify left bottom)
				(hide yes)
			)
		)
		(property "Author" "Antmicro"
			(at 125.73 236.855 0)
			(effects
				(font
					(size 1.27 1.27)
					(thickness 0.15)
				)
				(justify left bottom)
				(hide yes)
			)
		)
		(property "License" "Apache-2.0"
			(at 125.73 239.395 0)
			(effects
				(font
					(size 1.27 1.27)
					(thickness 0.15)
				)
				(justify left bottom)
				(hide yes)
			)
		)
		(pin "1"
		)
		(instances
			(project "sodimm-ddr5-tester"
				(path ""
					(reference "#PWR0261")
					(unit 1)
				)
			)
		)
	)
	(symbol
		(lib_id "antmicropower:+3V3")
		(at 327.66 138.43 0)
		(unit 1)
		(exclude_from_sim no)
		(in_bom yes)
		(on_board yes)
		(dnp no)
		(property "Reference" "#PWR0249"
			(at 327.66 142.24 0)
			(effects
				(font
					(size 1.27 1.27)
				)
				(hide yes)
			)
		)
		(property "Value" "+3V3"
			(at 324.485 135.89 0)
			(effects
				(font
					(size 1.27 1.27)
					(thickness 0.15)
				)
				(justify left bottom)
			)
		)
		(property "Footprint" ""
			(at 342.9 146.05 0)
			(effects
				(font
					(size 1.27 1.27)
					(thickness 0.15)
				)
				(justify left bottom)
				(hide yes)
			)
		)
		(property "Datasheet" ""
			(at 342.9 148.59 0)
			(effects
				(font
					(size 1.27 1.27)
					(thickness 0.15)
				)
				(justify left bottom)
				(hide yes)
			)
		)
		(property "Description" ""
			(at 327.66 138.43 0)
			(effects
				(font
					(size 1.27 1.27)
				)
			)
		)
		(property "Author" "Antmicro"
			(at 342.9 140.97 0)
			(effects
				(font
					(size 1.27 1.27)
					(thickness 0.15)
				)
				(justify left bottom)
				(hide yes)
			)
		)
		(property "License" "Apache-2.0"
			(at 342.9 143.51 0)
			(effects
				(font
					(size 1.27 1.27)
					(thickness 0.15)
				)
				(justify left bottom)
				(hide yes)
			)
		)
		(pin "1"
		)
		(instances
			(project "sodimm-ddr5-tester"
				(path ""
					(reference "#PWR0249")
					(unit 1)
				)
			)
		)
	)
	(symbol
		(lib_id "antmicroFerriteBeadsandChips:FB_120Z_2A_Murata-BLM18PG_0603")
		(at 257.81 91.44 0)
		(mirror y)
		(unit 1)
		(exclude_from_sim no)
		(in_bom yes)
		(on_board yes)
		(dnp no)
		(fields_autoplaced yes)
		(property "Reference" "FB6"
			(at 255.3081 86.045 0)
			(effects
				(font
					(size 1.27 1.27)
					(thickness 0.15)
				)
			)
		)
		(property "Value" "FB_120Z_2A_Murata-BLM18PG_0603"
			(at 242.57 93.98 0)
			(effects
				(font
					(size 1.27 1.27)
					(thickness 0.15)
				)
				(justify left bottom)
				(hide yes)
			)
		)
		(property "Footprint" "antmicro-footprints:FB_0603_1608Metric"
			(at 242.57 99.06 0)
			(effects
				(font
					(size 1.27 1.27)
					(thickness 0.15)
				)
				(justify left bottom)
				(hide yes)
			)
		)
		(property "Datasheet" "https://www.murata.com/en-us/products/productdata/8796738650142/ENFA0003.pdf"
			(at 242.57 101.6 0)
			(effects
				(font
					(size 1.27 1.27)
					(thickness 0.15)
				)
				(justify left bottom)
				(hide yes)
			)
		)
		(property "Description" ""
			(at 257.81 91.44 0)
			(effects
				(font
					(size 1.27 1.27)
				)
			)
		)
		(property "Val" "120Z/2A"
			(at 255.3081 88.5753 0)
			(effects
				(font
					(size 1.27 1.27)
				)
			)
		)
		(property "MPN" "BLM18PG121SN1D"
			(at 242.57 104.14 0)
			(effects
				(font
					(size 1.27 1.27)
					(thickness 0.15)
				)
				(justify left bottom)
				(hide yes)
			)
		)
		(property "Manufacturer" "Murata"
			(at 242.57 106.68 0)
			(effects
				(font
					(size 1.27 1.27)
					(thickness 0.15)
				)
				(justify left bottom)
				(hide yes)
			)
		)
		(property "Author" "Antmicro"
			(at 242.57 109.22 0)
			(effects
				(font
					(size 1.27 1.27)
					(thickness 0.15)
				)
				(justify left bottom)
				(hide yes)
			)
		)
		(property "License" "Apache-2.0"
			(at 242.57 111.76 0)
			(effects
				(font
					(size 1.27 1.27)
					(thickness 0.15)
				)
				(justify left bottom)
				(hide yes)
			)
		)
		(pin "1"
		)
		(pin "2"
		)
		(instances
			(project "sodimm-ddr5-tester"
				(path ""
					(reference "FB6")
					(unit 1)
				)
			)
		)
	)
	(symbol
		(lib_id "antmicropower:GND")
		(at 284.48 152.4 0)
		(unit 1)
		(exclude_from_sim no)
		(in_bom yes)
		(on_board yes)
		(dnp no)
		(property "Reference" "#PWR020"
			(at 284.48 158.75 0)
			(effects
				(font
					(size 1.27 1.27)
				)
				(hide yes)
			)
		)
		(property "Value" "GND"
			(at 282.448 156.464 0)
			(effects
				(font
					(size 1.27 1.27)
					(thickness 0.15)
				)
				(justify left)
			)
		)
		(property "Footprint" ""
			(at 293.37 160.02 0)
			(effects
				(font
					(size 1.27 1.27)
					(thickness 0.15)
				)
				(justify left bottom)
				(hide yes)
			)
		)
		(property "Datasheet" ""
			(at 293.37 165.1 0)
			(effects
				(font
					(size 1.27 1.27)
					(thickness 0.15)
				)
				(justify left bottom)
				(hide yes)
			)
		)
		(property "Description" ""
			(at 293.37 167.64 0)
			(effects
				(font
					(size 1.27 1.27)
				)
				(justify left bottom)
				(hide yes)
			)
		)
		(property "Author" "Antmicro"
			(at 293.37 160.02 0)
			(effects
				(font
					(size 1.27 1.27)
					(thickness 0.15)
				)
				(justify left bottom)
				(hide yes)
			)
		)
		(property "License" "Apache-2.0"
			(at 293.37 162.56 0)
			(effects
				(font
					(size 1.27 1.27)
					(thickness 0.15)
				)
				(justify left bottom)
				(hide yes)
			)
		)
		(pin "1"
		)
		(instances
			(project "sodimm-ddr5-tester"
				(path ""
					(reference "#PWR020")
					(unit 1)
				)
			)
		)
	)
	(symbol
		(lib_id "antmicroCapacitors0402:C_18p_0402")
		(at 109.22 160.02 90)
		(unit 1)
		(exclude_from_sim no)
		(in_bom yes)
		(on_board yes)
		(dnp no)
		(fields_autoplaced yes)
		(property "Reference" "C162"
			(at 106.896 156.643 90)
			(effects
				(font
					(size 1.27 1.27)
					(thickness 0.15)
				)
				(justify left)
			)
		)
		(property "Value" "C_18p_0402"
			(at 119.38 139.7 0)
			(effects
				(font
					(size 1.27 1.27)
					(thickness 0.15)
				)
				(justify left bottom)
				(hide yes)
			)
		)
		(property "Footprint" "antmicro-footprints:C_0402_1005Metric"
			(at 121.92 139.7 0)
			(effects
				(font
					(size 1.27 1.27)
					(thickness 0.15)
				)
				(justify left bottom)
				(hide yes)
			)
		)
		(property "Datasheet" "https://product.samsungsem.com/mlcc/CL05C180JB51PN.do"
			(at 124.46 139.7 0)
			(effects
				(font
					(size 1.27 1.27)
					(thickness 0.15)
				)
				(justify left bottom)
				(hide yes)
			)
		)
		(property "Description" ""
			(at 109.22 160.02 0)
			(effects
				(font
					(size 1.27 1.27)
				)
			)
		)
		(property "MPN" "CL05C180JB51PNC"
			(at 127 139.7 0)
			(effects
				(font
					(size 1.27 1.27)
					(thickness 0.15)
				)
				(justify left bottom)
				(hide yes)
			)
		)
		(property "Manufacturer" "Samsung Electro-Mechanics"
			(at 129.54 139.7 0)
			(effects
				(font
					(size 1.27 1.27)
					(thickness 0.15)
				)
				(justify left bottom)
				(hide yes)
			)
		)
		(property "License" "Apache-2.0"
			(at 132.08 139.7 0)
			(effects
				(font
					(size 1.27 1.27)
					(thickness 0.15)
				)
				(justify left bottom)
				(hide yes)
			)
		)
		(property "Author" "Antmicro"
			(at 134.62 139.7 0)
			(effects
				(font
					(size 1.27 1.27)
					(thickness 0.15)
				)
				(justify left bottom)
				(hide yes)
			)
		)
		(property "Val" "18p"
			(at 106.896 159.1667 90)
			(effects
				(font
					(size 1.27 1.27)
					(thickness 0.15)
				)
				(justify left)
			)
		)
		(property "Voltage" ""
			(at 137.16 139.7 0)
			(effects
				(font
					(size 1.27 1.27)
				)
				(justify left bottom)
				(hide yes)
			)
		)
		(property "Dielectric" ""
			(at 139.7 139.7 0)
			(effects
				(font
					(size 1.27 1.27)
				)
				(justify left bottom)
				(hide yes)
			)
		)
		(pin "1"
		)
		(pin "2"
		)
		(instances
			(project "sodimm-ddr5-tester"
				(path ""
					(reference "C162")
					(unit 1)
				)
			)
		)
	)
	(symbol
		(lib_id "antmicroCapacitors0402:C_100n_0402")
		(at 280.67 135.89 0)
		(unit 1)
		(exclude_from_sim no)
		(in_bom yes)
		(on_board yes)
		(dnp no)
		(property "Reference" "C137"
			(at 279.4 134.366 0)
			(effects
				(font
					(size 1.27 1.27)
					(thickness 0.15)
				)
			)
		)
		(property "Value" "C_100n_0402"
			(at 300.99 146.05 0)
			(effects
				(font
					(size 1.27 1.27)
					(thickness 0.15)
				)
				(justify left bottom)
				(hide yes)
			)
		)
		(property "Footprint" "antmicro-footprints:C_0402_1005Metric"
			(at 300.99 148.59 0)
			(effects
				(font
					(size 1.27 1.27)
					(thickness 0.15)
				)
				(justify left bottom)
				(hide yes)
			)
		)
		(property "Datasheet" "https://www.murata.com/products/productdetail?partno=GRM155R61H104KE14%23"
			(at 300.99 151.13 0)
			(effects
				(font
					(size 1.27 1.27)
					(thickness 0.15)
				)
				(justify left bottom)
				(hide yes)
			)
		)
		(property "Description" ""
			(at 280.67 135.89 0)
			(effects
				(font
					(size 1.27 1.27)
				)
			)
		)
		(property "MPN" "GRM155R61H104KE14D"
			(at 300.99 153.67 0)
			(effects
				(font
					(size 1.27 1.27)
					(thickness 0.15)
				)
				(justify left bottom)
				(hide yes)
			)
		)
		(property "Manufacturer" "Murata"
			(at 300.99 156.21 0)
			(effects
				(font
					(size 1.27 1.27)
					(thickness 0.15)
				)
				(justify left bottom)
				(hide yes)
			)
		)
		(property "License" "Apache-2.0"
			(at 300.99 158.75 0)
			(effects
				(font
					(size 1.27 1.27)
					(thickness 0.15)
				)
				(justify left bottom)
				(hide yes)
			)
		)
		(property "Author" "Antmicro"
			(at 300.99 161.29 0)
			(effects
				(font
					(size 1.27 1.27)
					(thickness 0.15)
				)
				(justify left bottom)
				(hide yes)
			)
		)
		(property "Val" "100n"
			(at 286.766 134.366 0)
			(effects
				(font
					(size 1.27 1.27)
					(thickness 0.15)
				)
			)
		)
		(property "Voltage" "50V"
			(at 300.99 163.83 0)
			(effects
				(font
					(size 1.27 1.27)
				)
				(justify left bottom)
				(hide yes)
			)
		)
		(property "Dielectric" "X5R"
			(at 300.99 166.37 0)
			(effects
				(font
					(size 1.27 1.27)
				)
				(justify left bottom)
				(hide yes)
			)
		)
		(pin "1"
		)
		(pin "2"
		)
		(instances
			(project "sodimm-ddr5-tester"
				(path ""
					(reference "C137")
					(unit 1)
				)
			)
		)
	)
	(symbol
		(lib_id "antmicroCapacitors0402:C_100n_0402")
		(at 278.13 138.43 0)
		(unit 1)
		(exclude_from_sim no)
		(in_bom yes)
		(on_board yes)
		(dnp no)
		(property "Reference" "C135"
			(at 277.114 139.954 0)
			(effects
				(font
					(size 1.27 1.27)
					(thickness 0.15)
				)
			)
		)
		(property "Value" "C_100n_0402"
			(at 298.45 148.59 0)
			(effects
				(font
					(size 1.27 1.27)
					(thickness 0.15)
				)
				(justify left bottom)
				(hide yes)
			)
		)
		(property "Footprint" "antmicro-footprints:C_0402_1005Metric"
			(at 298.45 151.13 0)
			(effects
				(font
					(size 1.27 1.27)
					(thickness 0.15)
				)
				(justify left bottom)
				(hide yes)
			)
		)
		(property "Datasheet" "https://www.murata.com/products/productdetail?partno=GRM155R61H104KE14%23"
			(at 298.45 153.67 0)
			(effects
				(font
					(size 1.27 1.27)
					(thickness 0.15)
				)
				(justify left bottom)
				(hide yes)
			)
		)
		(property "Description" ""
			(at 278.13 138.43 0)
			(effects
				(font
					(size 1.27 1.27)
				)
			)
		)
		(property "MPN" "GRM155R61H104KE14D"
			(at 298.45 156.21 0)
			(effects
				(font
					(size 1.27 1.27)
					(thickness 0.15)
				)
				(justify left bottom)
				(hide yes)
			)
		)
		(property "Manufacturer" "Murata"
			(at 298.45 158.75 0)
			(effects
				(font
					(size 1.27 1.27)
					(thickness 0.15)
				)
				(justify left bottom)
				(hide yes)
			)
		)
		(property "License" "Apache-2.0"
			(at 298.45 161.29 0)
			(effects
				(font
					(size 1.27 1.27)
					(thickness 0.15)
				)
				(justify left bottom)
				(hide yes)
			)
		)
		(property "Author" "Antmicro"
			(at 298.45 163.83 0)
			(effects
				(font
					(size 1.27 1.27)
					(thickness 0.15)
				)
				(justify left bottom)
				(hide yes)
			)
		)
		(property "Val" "100n"
			(at 283.972 139.954 0)
			(effects
				(font
					(size 1.27 1.27)
					(thickness 0.15)
				)
			)
		)
		(property "Voltage" "50V"
			(at 298.45 166.37 0)
			(effects
				(font
					(size 1.27 1.27)
				)
				(justify left bottom)
				(hide yes)
			)
		)
		(property "Dielectric" "X5R"
			(at 298.45 168.91 0)
			(effects
				(font
					(size 1.27 1.27)
				)
				(justify left bottom)
				(hide yes)
			)
		)
		(pin "1"
		)
		(pin "2"
		)
		(instances
			(project "sodimm-ddr5-tester"
				(path ""
					(reference "C135")
					(unit 1)
				)
			)
		)
	)
	(symbol
		(lib_id "antmicroResistors0402:R_10k_0402")
		(at 61.595 206.375 0)
		(mirror y)
		(unit 1)
		(exclude_from_sim no)
		(in_bom yes)
		(on_board yes)
		(dnp no)
		(property "Reference" "R104"
			(at 65.405 205.105 0)
			(effects
				(font
					(size 1.27 1.27)
				)
			)
		)
		(property "Value" "R_10k_0402"
			(at 41.275 219.075 0)
			(effects
				(font
					(size 1.27 1.27)
					(thickness 0.15)
				)
				(justify left bottom)
				(hide yes)
			)
		)
		(property "Footprint" "antmicro-footprints:R_0402_1005Metric"
			(at 41.275 221.615 0)
			(effects
				(font
					(size 1.27 1.27)
					(thickness 0.15)
				)
				(justify left bottom)
				(hide yes)
			)
		)
		(property "Datasheet" "https://www.bourns.com/docs/product-datasheets/cr.pdf"
			(at 41.275 224.155 0)
			(effects
				(font
					(size 1.27 1.27)
					(thickness 0.15)
				)
				(justify left bottom)
				(hide yes)
			)
		)
		(property "Description" ""
			(at 61.595 206.375 0)
			(effects
				(font
					(size 1.27 1.27)
				)
			)
		)
		(property "Manufacturer" "Bourns"
			(at 41.275 229.235 0)
			(effects
				(font
					(size 1.27 1.27)
					(thickness 0.15)
				)
				(justify left bottom)
				(hide yes)
			)
		)
		(property "MPN" "CR0402-FX-1002GLF"
			(at 41.275 226.695 0)
			(effects
				(font
					(size 1.27 1.27)
					(thickness 0.15)
				)
				(justify left bottom)
				(hide yes)
			)
		)
		(property "Val" "10k"
			(at 54.61 205.105 0)
			(effects
				(font
					(size 1.27 1.27)
					(thickness 0.15)
				)
			)
		)
		(property "License" "Apache-2.0"
			(at 41.275 231.775 0)
			(effects
				(font
					(size 1.27 1.27)
					(thickness 0.15)
				)
				(justify left bottom)
				(hide yes)
			)
		)
		(property "Author" "Antmicro"
			(at 41.275 234.315 0)
			(effects
				(font
					(size 1.27 1.27)
					(thickness 0.15)
				)
				(justify left bottom)
				(hide yes)
			)
		)
		(property "Tolerance" "1%"
			(at 41.275 216.535 0)
			(effects
				(font
					(size 1.27 1.27)
				)
				(justify left bottom)
				(hide yes)
			)
		)
		(pin "1"
		)
		(pin "2"
		)
		(instances
			(project "sodimm-ddr5-tester"
				(path ""
					(reference "R104")
					(unit 1)
				)
			)
		)
	)
	(symbol
		(lib_id "antmicropower:+3V3")
		(at 327.66 113.03 0)
		(unit 1)
		(exclude_from_sim no)
		(in_bom yes)
		(on_board yes)
		(dnp no)
		(property "Reference" "#PWR019"
			(at 327.66 116.84 0)
			(effects
				(font
					(size 1.27 1.27)
				)
				(hide yes)
			)
		)
		(property "Value" "+3V3"
			(at 324.485 110.49 0)
			(effects
				(font
					(size 1.27 1.27)
					(thickness 0.15)
				)
				(justify left bottom)
			)
		)
		(property "Footprint" ""
			(at 342.9 120.65 0)
			(effects
				(font
					(size 1.27 1.27)
					(thickness 0.15)
				)
				(justify left bottom)
				(hide yes)
			)
		)
		(property "Datasheet" ""
			(at 342.9 123.19 0)
			(effects
				(font
					(size 1.27 1.27)
					(thickness 0.15)
				)
				(justify left bottom)
				(hide yes)
			)
		)
		(property "Description" ""
			(at 327.66 113.03 0)
			(effects
				(font
					(size 1.27 1.27)
				)
			)
		)
		(property "Author" "Antmicro"
			(at 342.9 115.57 0)
			(effects
				(font
					(size 1.27 1.27)
					(thickness 0.15)
				)
				(justify left bottom)
				(hide yes)
			)
		)
		(property "License" "Apache-2.0"
			(at 342.9 118.11 0)
			(effects
				(font
					(size 1.27 1.27)
					(thickness 0.15)
				)
				(justify left bottom)
				(hide yes)
			)
		)
		(pin "1"
		)
		(instances
			(project "sodimm-ddr5-tester"
				(path ""
					(reference "#PWR019")
					(unit 1)
				)
			)
		)
	)
	(symbol
		(lib_id "antmicropower:GND")
		(at 223.52 62.865 0)
		(mirror y)
		(unit 1)
		(exclude_from_sim no)
		(in_bom yes)
		(on_board yes)
		(dnp no)
		(fields_autoplaced yes)
		(property "Reference" "#PWR0417"
			(at 223.52 69.215 0)
			(effects
				(font
					(size 1.27 1.27)
				)
				(hide yes)
			)
		)
		(property "Value" "GND"
			(at 226.06 64.135 0)
			(effects
				(font
					(size 1.27 1.27)
					(thickness 0.15)
				)
				(justify right)
			)
		)
		(property "Footprint" ""
			(at 214.63 70.485 0)
			(effects
				(font
					(size 1.27 1.27)
					(thickness 0.15)
				)
				(justify left bottom)
				(hide yes)
			)
		)
		(property "Datasheet" ""
			(at 214.63 75.565 0)
			(effects
				(font
					(size 1.27 1.27)
					(thickness 0.15)
				)
				(justify left bottom)
				(hide yes)
			)
		)
		(property "Description" ""
			(at 214.63 78.105 0)
			(effects
				(font
					(size 1.27 1.27)
				)
				(justify left bottom)
				(hide yes)
			)
		)
		(property "Author" "Antmicro"
			(at 214.63 70.485 0)
			(effects
				(font
					(size 1.27 1.27)
					(thickness 0.15)
				)
				(justify left bottom)
				(hide yes)
			)
		)
		(property "License" "Apache-2.0"
			(at 214.63 73.025 0)
			(effects
				(font
					(size 1.27 1.27)
					(thickness 0.15)
				)
				(justify left bottom)
				(hide yes)
			)
		)
		(pin "1"
		)
		(instances
			(project "sodimm-ddr5-tester"
				(path ""
					(reference "#PWR0417")
					(unit 1)
				)
			)
		)
	)
	(symbol
		(lib_id "antmicroResistors0402:R_10k_0402")
		(at 61.595 225.425 0)
		(mirror y)
		(unit 1)
		(exclude_from_sim no)
		(in_bom no)
		(on_board yes)
		(dnp yes)
		(property "Reference" "R105"
			(at 65.405 224.155 0)
			(effects
				(font
					(size 1.27 1.27)
				)
			)
		)
		(property "Value" "R_10k_0402"
			(at 41.275 238.125 0)
			(effects
				(font
					(size 1.27 1.27)
					(thickness 0.15)
				)
				(justify left bottom)
				(hide yes)
			)
		)
		(property "Footprint" "antmicro-footprints:R_0402_1005Metric"
			(at 41.275 240.665 0)
			(effects
				(font
					(size 1.27 1.27)
					(thickness 0.15)
				)
				(justify left bottom)
				(hide yes)
			)
		)
		(property "Datasheet" "https://www.bourns.com/docs/product-datasheets/cr.pdf"
			(at 41.275 243.205 0)
			(effects
				(font
					(size 1.27 1.27)
					(thickness 0.15)
				)
				(justify left bottom)
				(hide yes)
			)
		)
		(property "Description" ""
			(at 61.595 225.425 0)
			(effects
				(font
					(size 1.27 1.27)
				)
			)
		)
		(property "Manufacturer" "Bourns"
			(at 41.275 248.285 0)
			(effects
				(font
					(size 1.27 1.27)
					(thickness 0.15)
				)
				(justify left bottom)
				(hide yes)
			)
		)
		(property "MPN" "CR0402-FX-1002GLF"
			(at 41.275 245.745 0)
			(effects
				(font
					(size 1.27 1.27)
					(thickness 0.15)
				)
				(justify left bottom)
				(hide yes)
			)
		)
		(property "Val" "10k"
			(at 54.61 224.155 0)
			(effects
				(font
					(size 1.27 1.27)
					(thickness 0.15)
				)
			)
		)
		(property "License" "Apache-2.0"
			(at 41.275 250.825 0)
			(effects
				(font
					(size 1.27 1.27)
					(thickness 0.15)
				)
				(justify left bottom)
				(hide yes)
			)
		)
		(property "Author" "Antmicro"
			(at 41.275 253.365 0)
			(effects
				(font
					(size 1.27 1.27)
					(thickness 0.15)
				)
				(justify left bottom)
				(hide yes)
			)
		)
		(property "Tolerance" "1%"
			(at 41.275 235.585 0)
			(effects
				(font
					(size 1.27 1.27)
				)
				(justify left bottom)
				(hide yes)
			)
		)
		(pin "1"
		)
		(pin "2"
		)
		(instances
			(project "sodimm-ddr5-tester"
				(path ""
					(reference "R105")
					(unit 1)
				)
			)
		)
	)
	(symbol
		(lib_id "antmicropower:GND")
		(at 95.885 57.785 0)
		(unit 1)
		(exclude_from_sim no)
		(in_bom yes)
		(on_board yes)
		(dnp no)
		(property "Reference" "#PWR0354"
			(at 95.885 64.135 0)
			(effects
				(font
					(size 1.27 1.27)
				)
				(hide yes)
			)
		)
		(property "Value" "GND"
			(at 93.98 62.23 0)
			(effects
				(font
					(size 1.27 1.27)
					(thickness 0.15)
				)
				(justify left bottom)
			)
		)
		(property "Footprint" ""
			(at 104.775 65.405 0)
			(effects
				(font
					(size 1.27 1.27)
					(thickness 0.15)
				)
				(justify left bottom)
				(hide yes)
			)
		)
		(property "Datasheet" ""
			(at 104.775 70.485 0)
			(effects
				(font
					(size 1.27 1.27)
					(thickness 0.15)
				)
				(justify left bottom)
				(hide yes)
			)
		)
		(property "Description" ""
			(at 104.775 73.025 0)
			(effects
				(font
					(size 1.27 1.27)
				)
				(justify left bottom)
				(hide yes)
			)
		)
		(property "Author" "Antmicro"
			(at 104.775 65.405 0)
			(effects
				(font
					(size 1.27 1.27)
					(thickness 0.15)
				)
				(justify left bottom)
				(hide yes)
			)
		)
		(property "License" "Apache-2.0"
			(at 104.775 67.945 0)
			(effects
				(font
					(size 1.27 1.27)
					(thickness 0.15)
				)
				(justify left bottom)
				(hide yes)
			)
		)
		(pin "1"
		)
		(instances
			(project "sodimm-ddr5-tester"
				(path ""
					(reference "#PWR0354")
					(unit 1)
				)
			)
		)
	)
	(symbol
		(lib_id "antmicropower:GND")
		(at 215.265 62.865 0)
		(mirror y)
		(unit 1)
		(exclude_from_sim no)
		(in_bom yes)
		(on_board yes)
		(dnp no)
		(fields_autoplaced yes)
		(property "Reference" "#PWR0418"
			(at 215.265 69.215 0)
			(effects
				(font
					(size 1.27 1.27)
				)
				(hide yes)
			)
		)
		(property "Value" "GND"
			(at 217.17 64.135 0)
			(effects
				(font
					(size 1.27 1.27)
					(thickness 0.15)
				)
				(justify right)
			)
		)
		(property "Footprint" ""
			(at 206.375 70.485 0)
			(effects
				(font
					(size 1.27 1.27)
					(thickness 0.15)
				)
				(justify left bottom)
				(hide yes)
			)
		)
		(property "Datasheet" ""
			(at 206.375 75.565 0)
			(effects
				(font
					(size 1.27 1.27)
					(thickness 0.15)
				)
				(justify left bottom)
				(hide yes)
			)
		)
		(property "Description" ""
			(at 206.375 78.105 0)
			(effects
				(font
					(size 1.27 1.27)
				)
				(justify left bottom)
				(hide yes)
			)
		)
		(property "Author" "Antmicro"
			(at 206.375 70.485 0)
			(effects
				(font
					(size 1.27 1.27)
					(thickness 0.15)
				)
				(justify left bottom)
				(hide yes)
			)
		)
		(property "License" "Apache-2.0"
			(at 206.375 73.025 0)
			(effects
				(font
					(size 1.27 1.27)
					(thickness 0.15)
				)
				(justify left bottom)
				(hide yes)
			)
		)
		(pin "1"
		)
		(instances
			(project "sodimm-ddr5-tester"
				(path ""
					(reference "#PWR0418")
					(unit 1)
				)
			)
		)
	)
	(symbol
		(lib_id "antmicropower:GND")
		(at 112.395 78.74 0)
		(unit 1)
		(exclude_from_sim no)
		(in_bom yes)
		(on_board yes)
		(dnp no)
		(fields_autoplaced yes)
		(property "Reference" "#PWR0405"
			(at 112.395 85.09 0)
			(effects
				(font
					(size 1.27 1.27)
				)
				(hide yes)
			)
		)
		(property "Value" "GND"
			(at 114.3 80.01 0)
			(effects
				(font
					(size 1.27 1.27)
					(thickness 0.15)
				)
				(justify left)
			)
		)
		(property "Footprint" ""
			(at 121.285 86.36 0)
			(effects
				(font
					(size 1.27 1.27)
					(thickness 0.15)
				)
				(justify left bottom)
				(hide yes)
			)
		)
		(property "Datasheet" ""
			(at 121.285 91.44 0)
			(effects
				(font
					(size 1.27 1.27)
					(thickness 0.15)
				)
				(justify left bottom)
				(hide yes)
			)
		)
		(property "Description" ""
			(at 121.285 93.98 0)
			(effects
				(font
					(size 1.27 1.27)
				)
				(justify left bottom)
				(hide yes)
			)
		)
		(property "Author" "Antmicro"
			(at 121.285 86.36 0)
			(effects
				(font
					(size 1.27 1.27)
					(thickness 0.15)
				)
				(justify left bottom)
				(hide yes)
			)
		)
		(property "License" "Apache-2.0"
			(at 121.285 88.9 0)
			(effects
				(font
					(size 1.27 1.27)
					(thickness 0.15)
				)
				(justify left bottom)
				(hide yes)
			)
		)
		(pin "1"
		)
		(instances
			(project "sodimm-ddr5-tester"
				(path ""
					(reference "#PWR0405")
					(unit 1)
				)
			)
		)
	)
	(symbol
		(lib_id "antmicropower:GND")
		(at 190.5 99.695 0)
		(unit 1)
		(exclude_from_sim no)
		(in_bom yes)
		(on_board yes)
		(dnp no)
		(fields_autoplaced yes)
		(property "Reference" "#PWR0414"
			(at 190.5 106.045 0)
			(effects
				(font
					(size 1.27 1.27)
				)
				(hide yes)
			)
		)
		(property "Value" "GND"
			(at 193.04 100.965 0)
			(effects
				(font
					(size 1.27 1.27)
					(thickness 0.15)
				)
				(justify left)
			)
		)
		(property "Footprint" ""
			(at 199.39 107.315 0)
			(effects
				(font
					(size 1.27 1.27)
					(thickness 0.15)
				)
				(justify left bottom)
				(hide yes)
			)
		)
		(property "Datasheet" ""
			(at 199.39 112.395 0)
			(effects
				(font
					(size 1.27 1.27)
					(thickness 0.15)
				)
				(justify left bottom)
				(hide yes)
			)
		)
		(property "Description" ""
			(at 199.39 114.935 0)
			(effects
				(font
					(size 1.27 1.27)
				)
				(justify left bottom)
				(hide yes)
			)
		)
		(property "Author" "Antmicro"
			(at 199.39 107.315 0)
			(effects
				(font
					(size 1.27 1.27)
					(thickness 0.15)
				)
				(justify left bottom)
				(hide yes)
			)
		)
		(property "License" "Apache-2.0"
			(at 199.39 109.855 0)
			(effects
				(font
					(size 1.27 1.27)
					(thickness 0.15)
				)
				(justify left bottom)
				(hide yes)
			)
		)
		(pin "1"
		)
		(instances
			(project "sodimm-ddr5-tester"
				(path ""
					(reference "#PWR0414")
					(unit 1)
				)
			)
		)
	)
	(symbol
		(lib_id "antmicropower:GND")
		(at 198.755 99.695 0)
		(unit 1)
		(exclude_from_sim no)
		(in_bom yes)
		(on_board yes)
		(dnp no)
		(fields_autoplaced yes)
		(property "Reference" "#PWR0413"
			(at 198.755 106.045 0)
			(effects
				(font
					(size 1.27 1.27)
				)
				(hide yes)
			)
		)
		(property "Value" "GND"
			(at 200.66 100.965 0)
			(effects
				(font
					(size 1.27 1.27)
					(thickness 0.15)
				)
				(justify left)
			)
		)
		(property "Footprint" ""
			(at 207.645 107.315 0)
			(effects
				(font
					(size 1.27 1.27)
					(thickness 0.15)
				)
				(justify left bottom)
				(hide yes)
			)
		)
		(property "Datasheet" ""
			(at 207.645 112.395 0)
			(effects
				(font
					(size 1.27 1.27)
					(thickness 0.15)
				)
				(justify left bottom)
				(hide yes)
			)
		)
		(property "Description" ""
			(at 207.645 114.935 0)
			(effects
				(font
					(size 1.27 1.27)
				)
				(justify left bottom)
				(hide yes)
			)
		)
		(property "Author" "Antmicro"
			(at 207.645 107.315 0)
			(effects
				(font
					(size 1.27 1.27)
					(thickness 0.15)
				)
				(justify left bottom)
				(hide yes)
			)
		)
		(property "License" "Apache-2.0"
			(at 207.645 109.855 0)
			(effects
				(font
					(size 1.27 1.27)
					(thickness 0.15)
				)
				(justify left bottom)
				(hide yes)
			)
		)
		(pin "1"
		)
		(instances
			(project "sodimm-ddr5-tester"
				(path ""
					(reference "#PWR0413")
					(unit 1)
				)
			)
		)
	)
	(symbol
		(lib_id "antmicropower:GND")
		(at 190.5 62.865 0)
		(mirror y)
		(unit 1)
		(exclude_from_sim no)
		(in_bom yes)
		(on_board yes)
		(dnp no)
		(fields_autoplaced yes)
		(property "Reference" "#PWR0411"
			(at 190.5 69.215 0)
			(effects
				(font
					(size 1.27 1.27)
				)
				(hide yes)
			)
		)
		(property "Value" "GND"
			(at 193.04 64.135 0)
			(effects
				(font
					(size 1.27 1.27)
					(thickness 0.15)
				)
				(justify right)
			)
		)
		(property "Footprint" ""
			(at 181.61 70.485 0)
			(effects
				(font
					(size 1.27 1.27)
					(thickness 0.15)
				)
				(justify left bottom)
				(hide yes)
			)
		)
		(property "Datasheet" ""
			(at 181.61 75.565 0)
			(effects
				(font
					(size 1.27 1.27)
					(thickness 0.15)
				)
				(justify left bottom)
				(hide yes)
			)
		)
		(property "Description" ""
			(at 181.61 78.105 0)
			(effects
				(font
					(size 1.27 1.27)
				)
				(justify left bottom)
				(hide yes)
			)
		)
		(property "Author" "Antmicro"
			(at 181.61 70.485 0)
			(effects
				(font
					(size 1.27 1.27)
					(thickness 0.15)
				)
				(justify left bottom)
				(hide yes)
			)
		)
		(property "License" "Apache-2.0"
			(at 181.61 73.025 0)
			(effects
				(font
					(size 1.27 1.27)
					(thickness 0.15)
				)
				(justify left bottom)
				(hide yes)
			)
		)
		(pin "1"
		)
		(instances
			(project "sodimm-ddr5-tester"
				(path ""
					(reference "#PWR0411")
					(unit 1)
				)
			)
		)
	)
	(symbol
		(lib_id "antmicropower:GND")
		(at 207.01 83.82 0)
		(unit 1)
		(exclude_from_sim no)
		(in_bom yes)
		(on_board yes)
		(dnp no)
		(fields_autoplaced yes)
		(property "Reference" "#PWR0416"
			(at 207.01 90.17 0)
			(effects
				(font
					(size 1.27 1.27)
				)
				(hide yes)
			)
		)
		(property "Value" "GND"
			(at 209.55 85.09 0)
			(effects
				(font
					(size 1.27 1.27)
					(thickness 0.15)
				)
				(justify left)
			)
		)
		(property "Footprint" ""
			(at 215.9 91.44 0)
			(effects
				(font
					(size 1.27 1.27)
					(thickness 0.15)
				)
				(justify left bottom)
				(hide yes)
			)
		)
		(property "Datasheet" ""
			(at 215.9 96.52 0)
			(effects
				(font
					(size 1.27 1.27)
					(thickness 0.15)
				)
				(justify left bottom)
				(hide yes)
			)
		)
		(property "Description" ""
			(at 215.9 99.06 0)
			(effects
				(font
					(size 1.27 1.27)
				)
				(justify left bottom)
				(hide yes)
			)
		)
		(property "Author" "Antmicro"
			(at 215.9 91.44 0)
			(effects
				(font
					(size 1.27 1.27)
					(thickness 0.15)
				)
				(justify left bottom)
				(hide yes)
			)
		)
		(property "License" "Apache-2.0"
			(at 215.9 93.98 0)
			(effects
				(font
					(size 1.27 1.27)
					(thickness 0.15)
				)
				(justify left bottom)
				(hide yes)
			)
		)
		(pin "1"
		)
		(instances
			(project "sodimm-ddr5-tester"
				(path ""
					(reference "#PWR0416")
					(unit 1)
				)
			)
		)
	)
	(symbol
		(lib_id "antmicropower:GND")
		(at 198.755 62.865 0)
		(mirror y)
		(unit 1)
		(exclude_from_sim no)
		(in_bom yes)
		(on_board yes)
		(dnp no)
		(fields_autoplaced yes)
		(property "Reference" "#PWR0410"
			(at 198.755 69.215 0)
			(effects
				(font
					(size 1.27 1.27)
				)
				(hide yes)
			)
		)
		(property "Value" "GND"
			(at 200.66 64.135 0)
			(effects
				(font
					(size 1.27 1.27)
					(thickness 0.15)
				)
				(justify right)
			)
		)
		(property "Footprint" ""
			(at 189.865 70.485 0)
			(effects
				(font
					(size 1.27 1.27)
					(thickness 0.15)
				)
				(justify left bottom)
				(hide yes)
			)
		)
		(property "Datasheet" ""
			(at 189.865 75.565 0)
			(effects
				(font
					(size 1.27 1.27)
					(thickness 0.15)
				)
				(justify left bottom)
				(hide yes)
			)
		)
		(property "Description" ""
			(at 189.865 78.105 0)
			(effects
				(font
					(size 1.27 1.27)
				)
				(justify left bottom)
				(hide yes)
			)
		)
		(property "Author" "Antmicro"
			(at 189.865 70.485 0)
			(effects
				(font
					(size 1.27 1.27)
					(thickness 0.15)
				)
				(justify left bottom)
				(hide yes)
			)
		)
		(property "License" "Apache-2.0"
			(at 189.865 73.025 0)
			(effects
				(font
					(size 1.27 1.27)
					(thickness 0.15)
				)
				(justify left bottom)
				(hide yes)
			)
		)
		(pin "1"
		)
		(instances
			(project "sodimm-ddr5-tester"
				(path ""
					(reference "#PWR0410")
					(unit 1)
				)
			)
		)
	)
	(symbol
		(lib_name "R_1M8_0402_1")
		(lib_id "antmicroResistors0402:R_1M8_0402")
		(at 118.11 144.78 180)
		(unit 1)
		(exclude_from_sim no)
		(in_bom yes)
		(on_board yes)
		(dnp no)
		(property "Reference" "R100"
			(at 120.396 143.51 0)
			(effects
				(font
					(size 1.27 1.27)
					(thickness 0.15)
				)
			)
		)
		(property "Value" "R_1M8_0402"
			(at 97.79 132.08 0)
			(effects
				(font
					(size 1.27 1.27)
					(thickness 0.15)
				)
				(justify left bottom)
				(hide yes)
			)
		)
		(property "Footprint" "antmicro-footprints:R_0402_1005Metric"
			(at 97.79 129.54 0)
			(effects
				(font
					(size 1.27 1.27)
					(thickness 0.15)
				)
				(justify left bottom)
				(hide yes)
			)
		)
		(property "Datasheet" "https://www.mouser.com/catalog/specsheets/YAGEO_PYu_RC_Group_51_RoHS_L_12.pdf"
			(at 97.79 127 0)
			(effects
				(font
					(size 1.27 1.27)
					(thickness 0.15)
				)
				(justify left bottom)
				(hide yes)
			)
		)
		(property "Description" "SMD Chip Resistor"
			(at 97.79 114.3 0)
			(effects
				(font
					(size 1.27 1.27)
				)
				(justify left bottom)
				(hide yes)
			)
		)
		(property "MPN" "RC0402FR-071M8L"
			(at 97.79 124.46 0)
			(effects
				(font
					(size 1.27 1.27)
					(thickness 0.15)
				)
				(justify left bottom)
				(hide yes)
			)
		)
		(property "Manufacturer" "YAGEO"
			(at 97.79 121.92 0)
			(effects
				(font
					(size 1.27 1.27)
					(thickness 0.15)
				)
				(justify left bottom)
				(hide yes)
			)
		)
		(property "License" "Apache-2.0"
			(at 97.79 119.38 0)
			(effects
				(font
					(size 1.27 1.27)
					(thickness 0.15)
				)
				(justify left bottom)
				(hide yes)
			)
		)
		(property "Author" "Antmicro"
			(at 97.79 116.84 0)
			(effects
				(font
					(size 1.27 1.27)
					(thickness 0.15)
				)
				(justify left bottom)
				(hide yes)
			)
		)
		(property "Val" "1M8"
			(at 111.506 143.764 0)
			(effects
				(font
					(size 1.27 1.27)
					(thickness 0.15)
				)
			)
		)
		(property "Tolerance" "1%"
			(at 97.79 134.62 0)
			(effects
				(font
					(size 1.27 1.27)
				)
				(justify left bottom)
				(hide yes)
			)
		)
		(pin "2"
		)
		(pin "1"
		)
		(instances
			(project ""
				(path ""
					(reference "R100")
					(unit 1)
				)
			)
		)
	)
	(symbol
		(lib_id "antmicroCapacitors0402:C_100n_0402")
		(at 198.755 98.425 90)
		(unit 1)
		(exclude_from_sim no)
		(in_bom yes)
		(on_board yes)
		(dnp no)
		(property "Reference" "C157"
			(at 199.39 93.9963 90)
			(effects
				(font
					(size 1.27 1.27)
					(thickness 0.15)
				)
				(justify right)
			)
		)
		(property "Value" "C_100n_0402"
			(at 208.915 78.105 0)
			(effects
				(font
					(size 1.27 1.27)
					(thickness 0.15)
				)
				(justify left bottom)
				(hide yes)
			)
		)
		(property "Footprint" "antmicro-footprints:C_0402_1005Metric"
			(at 211.455 78.105 0)
			(effects
				(font
					(size 1.27 1.27)
					(thickness 0.15)
				)
				(justify left bottom)
				(hide yes)
			)
		)
		(property "Datasheet" "https://www.murata.com/products/productdetail?partno=GRM155R61H104KE14%23"
			(at 213.995 78.105 0)
			(effects
				(font
					(size 1.27 1.27)
					(thickness 0.15)
				)
				(justify left bottom)
				(hide yes)
			)
		)
		(property "Description" ""
			(at 198.755 98.425 0)
			(effects
				(font
					(size 1.27 1.27)
				)
			)
		)
		(property "MPN" "GRM155R61H104KE14D"
			(at 216.535 78.105 0)
			(effects
				(font
					(size 1.27 1.27)
					(thickness 0.15)
				)
				(justify left bottom)
				(hide yes)
			)
		)
		(property "Manufacturer" "Murata"
			(at 219.075 78.105 0)
			(effects
				(font
					(size 1.27 1.27)
					(thickness 0.15)
				)
				(justify left bottom)
				(hide yes)
			)
		)
		(property "License" "Apache-2.0"
			(at 221.615 78.105 0)
			(effects
				(font
					(size 1.27 1.27)
					(thickness 0.15)
				)
				(justify left bottom)
				(hide yes)
			)
		)
		(property "Author" "Antmicro"
			(at 224.155 78.105 0)
			(effects
				(font
					(size 1.27 1.27)
					(thickness 0.15)
				)
				(justify left bottom)
				(hide yes)
			)
		)
		(property "Val" "100n"
			(at 199.39 97.79 90)
			(effects
				(font
					(size 1.27 1.27)
					(thickness 0.15)
				)
				(justify right)
			)
		)
		(property "Voltage" "50V"
			(at 226.695 78.105 0)
			(effects
				(font
					(size 1.27 1.27)
				)
				(justify left bottom)
				(hide yes)
			)
		)
		(property "Dielectric" "X5R"
			(at 229.235 78.105 0)
			(effects
				(font
					(size 1.27 1.27)
				)
				(justify left bottom)
				(hide yes)
			)
		)
		(pin "1"
		)
		(pin "2"
		)
		(instances
			(project "sodimm-ddr5-tester"
				(path ""
					(reference "C157")
					(unit 1)
				)
			)
		)
	)
	(symbol
		(lib_id "antmicropower:GND")
		(at 104.14 78.74 0)
		(unit 1)
		(exclude_from_sim no)
		(in_bom yes)
		(on_board yes)
		(dnp no)
		(fields_autoplaced yes)
		(property "Reference" "#PWR0355"
			(at 104.14 85.09 0)
			(effects
				(font
					(size 1.27 1.27)
				)
				(hide yes)
			)
		)
		(property "Value" "GND"
			(at 106.68 80.01 0)
			(effects
				(font
					(size 1.27 1.27)
					(thickness 0.15)
				)
				(justify left)
			)
		)
		(property "Footprint" ""
			(at 113.03 86.36 0)
			(effects
				(font
					(size 1.27 1.27)
					(thickness 0.15)
				)
				(justify left bottom)
				(hide yes)
			)
		)
		(property "Datasheet" ""
			(at 113.03 91.44 0)
			(effects
				(font
					(size 1.27 1.27)
					(thickness 0.15)
				)
				(justify left bottom)
				(hide yes)
			)
		)
		(property "Description" ""
			(at 113.03 93.98 0)
			(effects
				(font
					(size 1.27 1.27)
				)
				(justify left bottom)
				(hide yes)
			)
		)
		(property "Author" "Antmicro"
			(at 113.03 86.36 0)
			(effects
				(font
					(size 1.27 1.27)
					(thickness 0.15)
				)
				(justify left bottom)
				(hide yes)
			)
		)
		(property "License" "Apache-2.0"
			(at 113.03 88.9 0)
			(effects
				(font
					(size 1.27 1.27)
					(thickness 0.15)
				)
				(justify left bottom)
				(hide yes)
			)
		)
		(pin "1"
		)
		(instances
			(project "sodimm-ddr5-tester"
				(path ""
					(reference "#PWR0355")
					(unit 1)
				)
			)
		)
	)
	(symbol
		(lib_id "antmicropower:GND")
		(at 104.14 57.785 0)
		(unit 1)
		(exclude_from_sim no)
		(in_bom yes)
		(on_board yes)
		(dnp no)
		(property "Reference" "#PWR0353"
			(at 104.14 64.135 0)
			(effects
				(font
					(size 1.27 1.27)
				)
				(hide yes)
			)
		)
		(property "Value" "GND"
			(at 102.235 62.23 0)
			(effects
				(font
					(size 1.27 1.27)
					(thickness 0.15)
				)
				(justify left bottom)
			)
		)
		(property "Footprint" ""
			(at 113.03 65.405 0)
			(effects
				(font
					(size 1.27 1.27)
					(thickness 0.15)
				)
				(justify left bottom)
				(hide yes)
			)
		)
		(property "Datasheet" ""
			(at 113.03 70.485 0)
			(effects
				(font
					(size 1.27 1.27)
					(thickness 0.15)
				)
				(justify left bottom)
				(hide yes)
			)
		)
		(property "Description" ""
			(at 113.03 73.025 0)
			(effects
				(font
					(size 1.27 1.27)
				)
				(justify left bottom)
				(hide yes)
			)
		)
		(property "Author" "Antmicro"
			(at 113.03 65.405 0)
			(effects
				(font
					(size 1.27 1.27)
					(thickness 0.15)
				)
				(justify left bottom)
				(hide yes)
			)
		)
		(property "License" "Apache-2.0"
			(at 113.03 67.945 0)
			(effects
				(font
					(size 1.27 1.27)
					(thickness 0.15)
				)
				(justify left bottom)
				(hide yes)
			)
		)
		(pin "1"
		)
		(instances
			(project "sodimm-ddr5-tester"
				(path ""
					(reference "#PWR0353")
					(unit 1)
				)
			)
		)
	)
	(symbol
		(lib_id "antmicropower:+3V3")
		(at 45.085 204.47 0)
		(mirror y)
		(unit 1)
		(exclude_from_sim no)
		(in_bom yes)
		(on_board yes)
		(dnp no)
		(property "Reference" "#PWR0258"
			(at 45.085 208.28 0)
			(effects
				(font
					(size 1.27 1.27)
				)
				(hide yes)
			)
		)
		(property "Value" "+3V3"
			(at 48.26 201.93 0)
			(effects
				(font
					(size 1.27 1.27)
					(thickness 0.15)
				)
				(justify left bottom)
			)
		)
		(property "Footprint" ""
			(at 29.845 212.09 0)
			(effects
				(font
					(size 1.27 1.27)
					(thickness 0.15)
				)
				(justify left bottom)
				(hide yes)
			)
		)
		(property "Datasheet" ""
			(at 29.845 214.63 0)
			(effects
				(font
					(size 1.27 1.27)
					(thickness 0.15)
				)
				(justify left bottom)
				(hide yes)
			)
		)
		(property "Description" ""
			(at 45.085 204.47 0)
			(effects
				(font
					(size 1.27 1.27)
				)
			)
		)
		(property "Author" "Antmicro"
			(at 29.845 207.01 0)
			(effects
				(font
					(size 1.27 1.27)
					(thickness 0.15)
				)
				(justify left bottom)
				(hide yes)
			)
		)
		(property "License" "Apache-2.0"
			(at 29.845 209.55 0)
			(effects
				(font
					(size 1.27 1.27)
					(thickness 0.15)
				)
				(justify left bottom)
				(hide yes)
			)
		)
		(pin "1"
		)
		(instances
			(project "sodimm-ddr5-tester"
				(path ""
					(reference "#PWR0258")
					(unit 1)
				)
			)
		)
	)
	(symbol
		(lib_id "antmicropower:PWR_FLAG")
		(at 243.84 75.565 0)
		(unit 1)
		(exclude_from_sim no)
		(in_bom yes)
		(on_board yes)
		(dnp no)
		(fields_autoplaced yes)
		(property "Reference" "#FLG0105"
			(at 243.84 73.66 0)
			(effects
				(font
					(size 1.27 1.27)
				)
				(hide yes)
			)
		)
		(property "Value" "PWR_FLAG"
			(at 243.84 71.9892 0)
			(effects
				(font
					(size 1.27 1.27)
				)
			)
		)
		(property "Footprint" ""
			(at 243.84 75.565 0)
			(effects
				(font
					(size 1.27 1.27)
				)
				(hide yes)
			)
		)
		(property "Datasheet" ""
			(at 243.84 75.565 0)
			(effects
				(font
					(size 1.27 1.27)
				)
				(hide yes)
			)
		)
		(property "Description" ""
			(at 243.84 75.565 0)
			(effects
				(font
					(size 1.27 1.27)
				)
			)
		)
		(pin "1"
		)
		(instances
			(project "sodimm-ddr5-tester"
				(path ""
					(reference "#FLG0105")
					(unit 1)
				)
			)
		)
	)
	(symbol
		(lib_id "antmicroFerriteBeadsandChips:FB_120Z_2A_Murata-BLM18PG_0603")
		(at 77.47 69.85 0)
		(unit 1)
		(exclude_from_sim no)
		(in_bom yes)
		(on_board yes)
		(dnp no)
		(fields_autoplaced yes)
		(property "Reference" "FB5"
			(at 79.9719 64.455 0)
			(effects
				(font
					(size 1.27 1.27)
					(thickness 0.15)
				)
			)
		)
		(property "Value" "FB_120Z_2A_Murata-BLM18PG_0603"
			(at 92.71 72.39 0)
			(effects
				(font
					(size 1.27 1.27)
					(thickness 0.15)
				)
				(justify left bottom)
				(hide yes)
			)
		)
		(property "Footprint" "antmicro-footprints:FB_0603_1608Metric"
			(at 92.71 77.47 0)
			(effects
				(font
					(size 1.27 1.27)
					(thickness 0.15)
				)
				(justify left bottom)
				(hide yes)
			)
		)
		(property "Datasheet" "https://www.murata.com/en-us/products/productdata/8796738650142/ENFA0003.pdf"
			(at 92.71 80.01 0)
			(effects
				(font
					(size 1.27 1.27)
					(thickness 0.15)
				)
				(justify left bottom)
				(hide yes)
			)
		)
		(property "Description" ""
			(at 77.47 69.85 0)
			(effects
				(font
					(size 1.27 1.27)
				)
			)
		)
		(property "Val" "120Z/2A"
			(at 79.9719 66.9853 0)
			(effects
				(font
					(size 1.27 1.27)
				)
			)
		)
		(property "MPN" "BLM18PG121SN1D"
			(at 92.71 82.55 0)
			(effects
				(font
					(size 1.27 1.27)
					(thickness 0.15)
				)
				(justify left bottom)
				(hide yes)
			)
		)
		(property "Manufacturer" "Murata"
			(at 92.71 85.09 0)
			(effects
				(font
					(size 1.27 1.27)
					(thickness 0.15)
				)
				(justify left bottom)
				(hide yes)
			)
		)
		(property "Author" "Antmicro"
			(at 92.71 87.63 0)
			(effects
				(font
					(size 1.27 1.27)
					(thickness 0.15)
				)
				(justify left bottom)
				(hide yes)
			)
		)
		(property "License" "Apache-2.0"
			(at 92.71 90.17 0)
			(effects
				(font
					(size 1.27 1.27)
					(thickness 0.15)
				)
				(justify left bottom)
				(hide yes)
			)
		)
		(pin "1"
		)
		(pin "2"
		)
		(instances
			(project "sodimm-ddr5-tester"
				(path ""
					(reference "FB5")
					(unit 1)
				)
			)
		)
	)
	(symbol
		(lib_id "antmicroResistors0402:R_10k_0402")
		(at 61.595 211.455 0)
		(mirror y)
		(unit 1)
		(exclude_from_sim no)
		(in_bom no)
		(on_board yes)
		(dnp yes)
		(property "Reference" "R102"
			(at 65.405 210.185 0)
			(effects
				(font
					(size 1.27 1.27)
				)
			)
		)
		(property "Value" "R_10k_0402"
			(at 41.275 224.155 0)
			(effects
				(font
					(size 1.27 1.27)
					(thickness 0.15)
				)
				(justify left bottom)
				(hide yes)
			)
		)
		(property "Footprint" "antmicro-footprints:R_0402_1005Metric"
			(at 41.275 226.695 0)
			(effects
				(font
					(size 1.27 1.27)
					(thickness 0.15)
				)
				(justify left bottom)
				(hide yes)
			)
		)
		(property "Datasheet" "https://www.bourns.com/docs/product-datasheets/cr.pdf"
			(at 41.275 229.235 0)
			(effects
				(font
					(size 1.27 1.27)
					(thickness 0.15)
				)
				(justify left bottom)
				(hide yes)
			)
		)
		(property "Description" ""
			(at 61.595 211.455 0)
			(effects
				(font
					(size 1.27 1.27)
				)
			)
		)
		(property "Manufacturer" "Bourns"
			(at 41.275 234.315 0)
			(effects
				(font
					(size 1.27 1.27)
					(thickness 0.15)
				)
				(justify left bottom)
				(hide yes)
			)
		)
		(property "MPN" "CR0402-FX-1002GLF"
			(at 41.275 231.775 0)
			(effects
				(font
					(size 1.27 1.27)
					(thickness 0.15)
				)
				(justify left bottom)
				(hide yes)
			)
		)
		(property "Val" "10k"
			(at 54.61 210.185 0)
			(effects
				(font
					(size 1.27 1.27)
					(thickness 0.15)
				)
			)
		)
		(property "License" "Apache-2.0"
			(at 41.275 236.855 0)
			(effects
				(font
					(size 1.27 1.27)
					(thickness 0.15)
				)
				(justify left bottom)
				(hide yes)
			)
		)
		(property "Author" "Antmicro"
			(at 41.275 239.395 0)
			(effects
				(font
					(size 1.27 1.27)
					(thickness 0.15)
				)
				(justify left bottom)
				(hide yes)
			)
		)
		(property "Tolerance" "1%"
			(at 41.275 221.615 0)
			(effects
				(font
					(size 1.27 1.27)
				)
				(justify left bottom)
				(hide yes)
			)
		)
		(pin "1"
		)
		(pin "2"
		)
		(instances
			(project "sodimm-ddr5-tester"
				(path ""
					(reference "R102")
					(unit 1)
				)
			)
		)
	)
	(symbol
		(lib_id "antmicropower:PWR_FLAG")
		(at 244.475 91.44 0)
		(unit 1)
		(exclude_from_sim no)
		(in_bom yes)
		(on_board yes)
		(dnp no)
		(fields_autoplaced yes)
		(property "Reference" "#FLG0106"
			(at 244.475 89.535 0)
			(effects
				(font
					(size 1.27 1.27)
				)
				(hide yes)
			)
		)
		(property "Value" "PWR_FLAG"
			(at 244.475 87.8642 0)
			(effects
				(font
					(size 1.27 1.27)
				)
			)
		)
		(property "Footprint" ""
			(at 244.475 91.44 0)
			(effects
				(font
					(size 1.27 1.27)
				)
				(hide yes)
			)
		)
		(property "Datasheet" ""
			(at 244.475 91.44 0)
			(effects
				(font
					(size 1.27 1.27)
				)
				(hide yes)
			)
		)
		(property "Description" ""
			(at 244.475 91.44 0)
			(effects
				(font
					(size 1.27 1.27)
				)
			)
		)
		(pin "1"
		)
		(instances
			(project "sodimm-ddr5-tester"
				(path ""
					(reference "#FLG0106")
					(unit 1)
				)
			)
		)
	)
	(symbol
		(lib_id "antmicroResistors0402:R_10k_0402")
		(at 61.595 222.25 0)
		(mirror y)
		(unit 1)
		(exclude_from_sim no)
		(in_bom yes)
		(on_board yes)
		(dnp no)
		(property "Reference" "R109"
			(at 65.405 220.98 0)
			(effects
				(font
					(size 1.27 1.27)
				)
			)
		)
		(property "Value" "R_10k_0402"
			(at 41.275 234.95 0)
			(effects
				(font
					(size 1.27 1.27)
					(thickness 0.15)
				)
				(justify left bottom)
				(hide yes)
			)
		)
		(property "Footprint" "antmicro-footprints:R_0402_1005Metric"
			(at 41.275 237.49 0)
			(effects
				(font
					(size 1.27 1.27)
					(thickness 0.15)
				)
				(justify left bottom)
				(hide yes)
			)
		)
		(property "Datasheet" "https://www.bourns.com/docs/product-datasheets/cr.pdf"
			(at 41.275 240.03 0)
			(effects
				(font
					(size 1.27 1.27)
					(thickness 0.15)
				)
				(justify left bottom)
				(hide yes)
			)
		)
		(property "Description" ""
			(at 61.595 222.25 0)
			(effects
				(font
					(size 1.27 1.27)
				)
			)
		)
		(property "Manufacturer" "Bourns"
			(at 41.275 245.11 0)
			(effects
				(font
					(size 1.27 1.27)
					(thickness 0.15)
				)
				(justify left bottom)
				(hide yes)
			)
		)
		(property "MPN" "CR0402-FX-1002GLF"
			(at 41.275 242.57 0)
			(effects
				(font
					(size 1.27 1.27)
					(thickness 0.15)
				)
				(justify left bottom)
				(hide yes)
			)
		)
		(property "Val" "10k"
			(at 54.61 220.98 0)
			(effects
				(font
					(size 1.27 1.27)
					(thickness 0.15)
				)
			)
		)
		(property "License" "Apache-2.0"
			(at 41.275 247.65 0)
			(effects
				(font
					(size 1.27 1.27)
					(thickness 0.15)
				)
				(justify left bottom)
				(hide yes)
			)
		)
		(property "Author" "Antmicro"
			(at 41.275 250.19 0)
			(effects
				(font
					(size 1.27 1.27)
					(thickness 0.15)
				)
				(justify left bottom)
				(hide yes)
			)
		)
		(property "Tolerance" "1%"
			(at 41.275 232.41 0)
			(effects
				(font
					(size 1.27 1.27)
				)
				(justify left bottom)
				(hide yes)
			)
		)
		(pin "1"
		)
		(pin "2"
		)
		(instances
			(project "sodimm-ddr5-tester"
				(path ""
					(reference "R109")
					(unit 1)
				)
			)
		)
	)
	(symbol
		(lib_id "antmicropower:GND")
		(at 266.065 266.065 0)
		(unit 1)
		(exclude_from_sim no)
		(in_bom yes)
		(on_board yes)
		(dnp no)
		(fields_autoplaced yes)
		(property "Reference" "#PWR0253"
			(at 266.065 272.415 0)
			(effects
				(font
					(size 1.27 1.27)
				)
				(hide yes)
			)
		)
		(property "Value" "GND"
			(at 267.97 267.335 0)
			(effects
				(font
					(size 1.27 1.27)
					(thickness 0.15)
				)
				(justify left)
			)
		)
		(property "Footprint" ""
			(at 274.955 273.685 0)
			(effects
				(font
					(size 1.27 1.27)
					(thickness 0.15)
				)
				(justify left bottom)
				(hide yes)
			)
		)
		(property "Datasheet" ""
			(at 274.955 278.765 0)
			(effects
				(font
					(size 1.27 1.27)
					(thickness 0.15)
				)
				(justify left bottom)
				(hide yes)
			)
		)
		(property "Description" ""
			(at 274.955 281.305 0)
			(effects
				(font
					(size 1.27 1.27)
				)
				(justify left bottom)
				(hide yes)
			)
		)
		(property "Author" "Antmicro"
			(at 274.955 273.685 0)
			(effects
				(font
					(size 1.27 1.27)
					(thickness 0.15)
				)
				(justify left bottom)
				(hide yes)
			)
		)
		(property "License" "Apache-2.0"
			(at 274.955 276.225 0)
			(effects
				(font
					(size 1.27 1.27)
					(thickness 0.15)
				)
				(justify left bottom)
				(hide yes)
			)
		)
		(pin "1"
		)
		(instances
			(project "sodimm-ddr5-tester"
				(path ""
					(reference "#PWR0253")
					(unit 1)
				)
			)
		)
	)
	(symbol
		(lib_id "antmicropower:+3V3")
		(at 277.495 260.985 0)
		(unit 1)
		(exclude_from_sim no)
		(in_bom yes)
		(on_board yes)
		(dnp no)
		(property "Reference" "#PWR0254"
			(at 277.495 264.795 0)
			(effects
				(font
					(size 1.27 1.27)
				)
				(hide yes)
			)
		)
		(property "Value" "+3V3"
			(at 274.32 258.445 0)
			(effects
				(font
					(size 1.27 1.27)
					(thickness 0.15)
				)
				(justify left bottom)
			)
		)
		(property "Footprint" ""
			(at 292.735 268.605 0)
			(effects
				(font
					(size 1.27 1.27)
					(thickness 0.15)
				)
				(justify left bottom)
				(hide yes)
			)
		)
		(property "Datasheet" ""
			(at 292.735 271.145 0)
			(effects
				(font
					(size 1.27 1.27)
					(thickness 0.15)
				)
				(justify left bottom)
				(hide yes)
			)
		)
		(property "Description" ""
			(at 277.495 260.985 0)
			(effects
				(font
					(size 1.27 1.27)
				)
			)
		)
		(property "Author" "Antmicro"
			(at 292.735 263.525 0)
			(effects
				(font
					(size 1.27 1.27)
					(thickness 0.15)
				)
				(justify left bottom)
				(hide yes)
			)
		)
		(property "License" "Apache-2.0"
			(at 292.735 266.065 0)
			(effects
				(font
					(size 1.27 1.27)
					(thickness 0.15)
				)
				(justify left bottom)
				(hide yes)
			)
		)
		(pin "1"
		)
		(instances
			(project "sodimm-ddr5-tester"
				(path ""
					(reference "#PWR0254")
					(unit 1)
				)
			)
		)
	)
	(symbol
		(lib_id "antmicropower:GND")
		(at 87.63 57.785 0)
		(unit 1)
		(exclude_from_sim no)
		(in_bom yes)
		(on_board yes)
		(dnp no)
		(property "Reference" "#PWR0406"
			(at 87.63 64.135 0)
			(effects
				(font
					(size 1.27 1.27)
				)
				(hide yes)
			)
		)
		(property "Value" "GND"
			(at 85.725 62.23 0)
			(effects
				(font
					(size 1.27 1.27)
					(thickness 0.15)
				)
				(justify left bottom)
			)
		)
		(property "Footprint" ""
			(at 96.52 65.405 0)
			(effects
				(font
					(size 1.27 1.27)
					(thickness 0.15)
				)
				(justify left bottom)
				(hide yes)
			)
		)
		(property "Datasheet" ""
			(at 96.52 70.485 0)
			(effects
				(font
					(size 1.27 1.27)
					(thickness 0.15)
				)
				(justify left bottom)
				(hide yes)
			)
		)
		(property "Description" ""
			(at 96.52 73.025 0)
			(effects
				(font
					(size 1.27 1.27)
				)
				(justify left bottom)
				(hide yes)
			)
		)
		(property "Author" "Antmicro"
			(at 96.52 65.405 0)
			(effects
				(font
					(size 1.27 1.27)
					(thickness 0.15)
				)
				(justify left bottom)
				(hide yes)
			)
		)
		(property "License" "Apache-2.0"
			(at 96.52 67.945 0)
			(effects
				(font
					(size 1.27 1.27)
					(thickness 0.15)
				)
				(justify left bottom)
				(hide yes)
			)
		)
		(pin "1"
		)
		(instances
			(project "sodimm-ddr5-tester"
				(path ""
					(reference "#PWR0406")
					(unit 1)
				)
			)
		)
	)
	(symbol
		(lib_id "antmicropower:GND")
		(at 190.5 83.82 0)
		(unit 1)
		(exclude_from_sim no)
		(in_bom yes)
		(on_board yes)
		(dnp no)
		(fields_autoplaced yes)
		(property "Reference" "#PWR0412"
			(at 190.5 90.17 0)
			(effects
				(font
					(size 1.27 1.27)
				)
				(hide yes)
			)
		)
		(property "Value" "GND"
			(at 193.04 85.09 0)
			(effects
				(font
					(size 1.27 1.27)
					(thickness 0.15)
				)
				(justify left)
			)
		)
		(property "Footprint" ""
			(at 199.39 91.44 0)
			(effects
				(font
					(size 1.27 1.27)
					(thickness 0.15)
				)
				(justify left bottom)
				(hide yes)
			)
		)
		(property "Datasheet" ""
			(at 199.39 96.52 0)
			(effects
				(font
					(size 1.27 1.27)
					(thickness 0.15)
				)
				(justify left bottom)
				(hide yes)
			)
		)
		(property "Description" ""
			(at 199.39 99.06 0)
			(effects
				(font
					(size 1.27 1.27)
				)
				(justify left bottom)
				(hide yes)
			)
		)
		(property "Author" "Antmicro"
			(at 199.39 91.44 0)
			(effects
				(font
					(size 1.27 1.27)
					(thickness 0.15)
				)
				(justify left bottom)
				(hide yes)
			)
		)
		(property "License" "Apache-2.0"
			(at 199.39 93.98 0)
			(effects
				(font
					(size 1.27 1.27)
					(thickness 0.15)
				)
				(justify left bottom)
				(hide yes)
			)
		)
		(pin "1"
		)
		(instances
			(project "sodimm-ddr5-tester"
				(path ""
					(reference "#PWR0412")
					(unit 1)
				)
			)
		)
	)
	(symbol
		(lib_id "antmicroResistors0402:R_10k_0402")
		(at 61.595 208.915 0)
		(mirror y)
		(unit 1)
		(exclude_from_sim no)
		(in_bom yes)
		(on_board yes)
		(dnp no)
		(property "Reference" "R103"
			(at 65.405 207.645 0)
			(effects
				(font
					(size 1.27 1.27)
				)
			)
		)
		(property "Value" "R_10k_0402"
			(at 41.275 221.615 0)
			(effects
				(font
					(size 1.27 1.27)
					(thickness 0.15)
				)
				(justify left bottom)
				(hide yes)
			)
		)
		(property "Footprint" "antmicro-footprints:R_0402_1005Metric"
			(at 41.275 224.155 0)
			(effects
				(font
					(size 1.27 1.27)
					(thickness 0.15)
				)
				(justify left bottom)
				(hide yes)
			)
		)
		(property "Datasheet" "https://www.bourns.com/docs/product-datasheets/cr.pdf"
			(at 41.275 226.695 0)
			(effects
				(font
					(size 1.27 1.27)
					(thickness 0.15)
				)
				(justify left bottom)
				(hide yes)
			)
		)
		(property "Description" ""
			(at 61.595 208.915 0)
			(effects
				(font
					(size 1.27 1.27)
				)
			)
		)
		(property "Manufacturer" "Bourns"
			(at 41.275 231.775 0)
			(effects
				(font
					(size 1.27 1.27)
					(thickness 0.15)
				)
				(justify left bottom)
				(hide yes)
			)
		)
		(property "MPN" "CR0402-FX-1002GLF"
			(at 41.275 229.235 0)
			(effects
				(font
					(size 1.27 1.27)
					(thickness 0.15)
				)
				(justify left bottom)
				(hide yes)
			)
		)
		(property "Val" "10k"
			(at 54.61 207.645 0)
			(effects
				(font
					(size 1.27 1.27)
					(thickness 0.15)
				)
			)
		)
		(property "License" "Apache-2.0"
			(at 41.275 234.315 0)
			(effects
				(font
					(size 1.27 1.27)
					(thickness 0.15)
				)
				(justify left bottom)
				(hide yes)
			)
		)
		(property "Author" "Antmicro"
			(at 41.275 236.855 0)
			(effects
				(font
					(size 1.27 1.27)
					(thickness 0.15)
				)
				(justify left bottom)
				(hide yes)
			)
		)
		(property "Tolerance" "1%"
			(at 41.275 219.075 0)
			(effects
				(font
					(size 1.27 1.27)
				)
				(justify left bottom)
				(hide yes)
			)
		)
		(pin "1"
		)
		(pin "2"
		)
		(instances
			(project "sodimm-ddr5-tester"
				(path ""
					(reference "R103")
					(unit 1)
				)
			)
		)
	)
	(symbol
		(lib_id "antmicropower:+1V2")
		(at 260.985 52.07 0)
		(mirror y)
		(unit 1)
		(exclude_from_sim no)
		(in_bom yes)
		(on_board yes)
		(dnp no)
		(fields_autoplaced yes)
		(property "Reference" "#PWR0244"
			(at 260.985 55.88 0)
			(effects
				(font
					(size 1.27 1.27)
				)
				(hide yes)
			)
		)
		(property "Value" "+1V2"
			(at 260.985 46.99 0)
			(effects
				(font
					(size 1.27 1.27)
				)
			)
		)
		(property "Footprint" ""
			(at 260.985 52.07 0)
			(effects
				(font
					(size 1.27 1.27)
				)
				(hide yes)
			)
		)
		(property "Datasheet" ""
			(at 260.985 52.07 0)
			(effects
				(font
					(size 1.27 1.27)
				)
				(hide yes)
			)
		)
		(property "Description" ""
			(at 260.985 52.07 0)
			(effects
				(font
					(size 1.27 1.27)
				)
			)
		)
		(pin "1"
		)
		(instances
			(project "sodimm-ddr5-tester"
				(path ""
					(reference "#PWR0244")
					(unit 1)
				)
			)
		)
	)
	(symbol
		(lib_id "antmicroCapacitors0402:C_100n_0402")
		(at 277.495 266.065 90)
		(unit 1)
		(exclude_from_sim no)
		(in_bom yes)
		(on_board yes)
		(dnp no)
		(fields_autoplaced yes)
		(property "Reference" "C161"
			(at 279.8191 262.688 90)
			(effects
				(font
					(size 1.27 1.27)
					(thickness 0.15)
				)
				(justify right)
			)
		)
		(property "Value" "C_100n_0402"
			(at 287.655 245.745 0)
			(effects
				(font
					(size 1.27 1.27)
					(thickness 0.15)
				)
				(justify left bottom)
				(hide yes)
			)
		)
		(property "Footprint" "antmicro-footprints:C_0402_1005Metric"
			(at 290.195 245.745 0)
			(effects
				(font
					(size 1.27 1.27)
					(thickness 0.15)
				)
				(justify left bottom)
				(hide yes)
			)
		)
		(property "Datasheet" "https://www.murata.com/products/productdetail?partno=GRM155R61H104KE14%23"
			(at 292.735 245.745 0)
			(effects
				(font
					(size 1.27 1.27)
					(thickness 0.15)
				)
				(justify left bottom)
				(hide yes)
			)
		)
		(property "Description" ""
			(at 277.495 266.065 0)
			(effects
				(font
					(size 1.27 1.27)
				)
			)
		)
		(property "MPN" "GRM155R61H104KE14D"
			(at 295.275 245.745 0)
			(effects
				(font
					(size 1.27 1.27)
					(thickness 0.15)
				)
				(justify left bottom)
				(hide yes)
			)
		)
		(property "Manufacturer" "Murata"
			(at 297.815 245.745 0)
			(effects
				(font
					(size 1.27 1.27)
					(thickness 0.15)
				)
				(justify left bottom)
				(hide yes)
			)
		)
		(property "License" "Apache-2.0"
			(at 300.355 245.745 0)
			(effects
				(font
					(size 1.27 1.27)
					(thickness 0.15)
				)
				(justify left bottom)
				(hide yes)
			)
		)
		(property "Author" "Antmicro"
			(at 302.895 245.745 0)
			(effects
				(font
					(size 1.27 1.27)
					(thickness 0.15)
				)
				(justify left bottom)
				(hide yes)
			)
		)
		(property "Val" "100n"
			(at 279.8191 265.2117 90)
			(effects
				(font
					(size 1.27 1.27)
					(thickness 0.15)
				)
				(justify right)
			)
		)
		(property "Voltage" "50V"
			(at 305.435 245.745 0)
			(effects
				(font
					(size 1.27 1.27)
				)
				(justify left bottom)
				(hide yes)
			)
		)
		(property "Dielectric" "X5R"
			(at 307.975 245.745 0)
			(effects
				(font
					(size 1.27 1.27)
				)
				(justify left bottom)
				(hide yes)
			)
		)
		(pin "1"
		)
		(pin "2"
		)
		(instances
			(project "sodimm-ddr5-tester"
				(path ""
					(reference "C161")
					(unit 1)
				)
			)
		)
	)
	(symbol
		(lib_id "antmicropower:GND")
		(at 112.395 57.785 0)
		(unit 1)
		(exclude_from_sim no)
		(in_bom yes)
		(on_board yes)
		(dnp no)
		(property "Reference" "#PWR0404"
			(at 112.395 64.135 0)
			(effects
				(font
					(size 1.27 1.27)
				)
				(hide yes)
			)
		)
		(property "Value" "GND"
			(at 110.49 62.23 0)
			(effects
				(font
					(size 1.27 1.27)
					(thickness 0.15)
				)
				(justify left bottom)
			)
		)
		(property "Footprint" ""
			(at 121.285 65.405 0)
			(effects
				(font
					(size 1.27 1.27)
					(thickness 0.15)
				)
				(justify left bottom)
				(hide yes)
			)
		)
		(property "Datasheet" ""
			(at 121.285 70.485 0)
			(effects
				(font
					(size 1.27 1.27)
					(thickness 0.15)
				)
				(justify left bottom)
				(hide yes)
			)
		)
		(property "Description" ""
			(at 121.285 73.025 0)
			(effects
				(font
					(size 1.27 1.27)
				)
				(justify left bottom)
				(hide yes)
			)
		)
		(property "Author" "Antmicro"
			(at 121.285 65.405 0)
			(effects
				(font
					(size 1.27 1.27)
					(thickness 0.15)
				)
				(justify left bottom)
				(hide yes)
			)
		)
		(property "License" "Apache-2.0"
			(at 121.285 67.945 0)
			(effects
				(font
					(size 1.27 1.27)
					(thickness 0.15)
				)
				(justify left bottom)
				(hide yes)
			)
		)
		(pin "1"
		)
		(instances
			(project "sodimm-ddr5-tester"
				(path ""
					(reference "#PWR0404")
					(unit 1)
				)
			)
		)
	)
	(symbol
		(lib_id "antmicroModularConnectorsJacks:RJ45_Abracon_ARJM11B1-502-AB-EW2")
		(at 289.56 114.3 0)
		(unit 1)
		(exclude_from_sim no)
		(in_bom yes)
		(on_board yes)
		(dnp no)
		(fields_autoplaced yes)
		(property "Reference" "J6"
			(at 300.99 106.68 0)
			(effects
				(font
					(size 1.27 1.27)
					(thickness 0.15)
				)
			)
		)
		(property "Value" "RJ45_Abracon_ARJM11B1-502-AB-EW2"
			(at 325.12 121.92 0)
			(effects
				(font
					(size 1.27 1.27)
					(thickness 0.15)
				)
				(justify left bottom)
				(hide yes)
			)
		)
		(property "Footprint" "antmicro-footprints:RJ45_ARJM11B1-502-AB-EW2_Horizontal"
			(at 325.12 124.46 0)
			(effects
				(font
					(size 1.27 1.27)
					(thickness 0.15)
				)
				(justify left bottom)
				(hide yes)
			)
		)
		(property "Datasheet" "https://www.mouser.com/datasheet/3/184/1/ARJM11.pdf"
			(at 325.12 127 0)
			(effects
				(font
					(size 1.27 1.27)
					(thickness 0.15)
				)
				(justify left bottom)
				(hide yes)
			)
		)
		(property "Description" "Modular Connectors / Ethernet Connectors RJ45 JACK W/MAG 1X1 1000BASE-T"
			(at 325.12 136.906 0)
			(effects
				(font
					(size 1.27 1.27)
				)
				(justify left bottom)
				(hide yes)
			)
		)
		(property "MPN" "ARJM11B1-502-AB-EW2"
			(at 300.99 109.22 0)
			(effects
				(font
					(size 1.27 1.27)
					(thickness 0.15)
				)
			)
		)
		(property "Manufacturer" "Abracon"
			(at 325.12 129.54 0)
			(effects
				(font
					(size 1.27 1.27)
					(thickness 0.15)
				)
				(justify left bottom)
				(hide yes)
			)
		)
		(property "Author" "Antmicro"
			(at 325.12 131.826 0)
			(effects
				(font
					(size 1.27 1.27)
					(thickness 0.15)
				)
				(justify left bottom)
				(hide yes)
			)
		)
		(property "License" "Apache-2.0"
			(at 325.12 134.366 0)
			(effects
				(font
					(size 1.27 1.27)
					(thickness 0.15)
				)
				(justify left bottom)
				(hide yes)
			)
		)
		(pin "10"
		)
		(pin "14"
		)
		(pin "5"
		)
		(pin "6"
		)
		(pin "12"
		)
		(pin "SH"
		)
		(pin "4"
		)
		(pin "2"
		)
		(pin "3"
		)
		(pin "1"
		)
		(pin "11"
		)
		(pin "7"
		)
		(pin "9"
		)
		(pin "8"
		)
		(pin "13"
		)
		(instances
			(project ""
				(path ""
					(reference "J6")
					(unit 1)
				)
			)
		)
	)
	(symbol
		(lib_id "antmicropower:GND")
		(at 231.775 62.865 0)
		(mirror y)
		(unit 1)
		(exclude_from_sim no)
		(in_bom yes)
		(on_board yes)
		(dnp no)
		(fields_autoplaced yes)
		(property "Reference" "#PWR0420"
			(at 231.775 69.215 0)
			(effects
				(font
					(size 1.27 1.27)
				)
				(hide yes)
			)
		)
		(property "Value" "GND"
			(at 233.68 64.135 0)
			(effects
				(font
					(size 1.27 1.27)
					(thickness 0.15)
				)
				(justify right)
			)
		)
		(property "Footprint" ""
			(at 222.885 70.485 0)
			(effects
				(font
					(size 1.27 1.27)
					(thickness 0.15)
				)
				(justify left bottom)
				(hide yes)
			)
		)
		(property "Datasheet" ""
			(at 222.885 75.565 0)
			(effects
				(font
					(size 1.27 1.27)
					(thickness 0.15)
				)
				(justify left bottom)
				(hide yes)
			)
		)
		(property "Description" ""
			(at 222.885 78.105 0)
			(effects
				(font
					(size 1.27 1.27)
				)
				(justify left bottom)
				(hide yes)
			)
		)
		(property "Author" "Antmicro"
			(at 222.885 70.485 0)
			(effects
				(font
					(size 1.27 1.27)
					(thickness 0.15)
				)
				(justify left bottom)
				(hide yes)
			)
		)
		(property "License" "Apache-2.0"
			(at 222.885 73.025 0)
			(effects
				(font
					(size 1.27 1.27)
					(thickness 0.15)
				)
				(justify left bottom)
				(hide yes)
			)
		)
		(pin "1"
		)
		(instances
			(project "sodimm-ddr5-tester"
				(path ""
					(reference "#PWR0420")
					(unit 1)
				)
			)
		)
	)
	(symbol
		(lib_id "antmicroCapacitors0402:C_100n_0402")
		(at 284.48 144.78 90)
		(mirror x)
		(unit 1)
		(exclude_from_sim no)
		(in_bom yes)
		(on_board yes)
		(dnp no)
		(property "Reference" "C234"
			(at 280.162 146.812 90)
			(effects
				(font
					(size 1.27 1.27)
				)
			)
		)
		(property "Value" "C_100n_0402"
			(at 294.64 165.1 0)
			(effects
				(font
					(size 1.27 1.27)
					(thickness 0.15)
				)
				(justify left bottom)
				(hide yes)
			)
		)
		(property "Footprint" "antmicro-footprints:C_0402_1005Metric"
			(at 297.18 165.1 0)
			(effects
				(font
					(size 1.27 1.27)
					(thickness 0.15)
				)
				(justify left bottom)
				(hide yes)
			)
		)
		(property "Datasheet" "https://www.murata.com/products/productdetail?partno=GRM155R61H104KE14%23"
			(at 299.72 165.1 0)
			(effects
				(font
					(size 1.27 1.27)
					(thickness 0.15)
				)
				(justify left bottom)
				(hide yes)
			)
		)
		(property "Description" ""
			(at 284.48 144.78 0)
			(effects
				(font
					(size 1.27 1.27)
				)
			)
		)
		(property "Manufacturer" "Murata"
			(at 304.8 165.1 0)
			(effects
				(font
					(size 1.27 1.27)
					(thickness 0.15)
				)
				(justify left bottom)
				(hide yes)
			)
		)
		(property "MPN" "GRM155R61H104KE14D"
			(at 302.26 165.1 0)
			(effects
				(font
					(size 1.27 1.27)
					(thickness 0.15)
				)
				(justify left bottom)
				(hide yes)
			)
		)
		(property "Val" "100n"
			(at 280.162 148.844 90)
			(effects
				(font
					(size 1.27 1.27)
					(thickness 0.15)
				)
			)
		)
		(property "License" "Apache-2.0"
			(at 307.34 165.1 0)
			(effects
				(font
					(size 1.27 1.27)
					(thickness 0.15)
				)
				(justify left bottom)
				(hide yes)
			)
		)
		(property "Author" "Antmicro"
			(at 309.88 165.1 0)
			(effects
				(font
					(size 1.27 1.27)
					(thickness 0.15)
				)
				(justify left bottom)
				(hide yes)
			)
		)
		(property "Voltage" "50V"
			(at 312.42 165.1 0)
			(effects
				(font
					(size 1.27 1.27)
				)
				(justify left bottom)
				(hide yes)
			)
		)
		(property "Dielectric" "X5R"
			(at 314.96 165.1 0)
			(effects
				(font
					(size 1.27 1.27)
				)
				(justify left bottom)
				(hide yes)
			)
		)
		(pin "1"
		)
		(pin "2"
		)
		(instances
			(project "sodimm-ddr5-tester"
				(path ""
					(reference "C234")
					(unit 1)
				)
			)
		)
	)
	(symbol
		(lib_id "antmicroFerriteBeadsandChips:FB_120Z_2A_Murata-BLM18PG_0603")
		(at 257.81 75.565 0)
		(mirror y)
		(unit 1)
		(exclude_from_sim no)
		(in_bom yes)
		(on_board yes)
		(dnp no)
		(fields_autoplaced yes)
		(property "Reference" "FB4"
			(at 255.3081 70.17 0)
			(effects
				(font
					(size 1.27 1.27)
					(thickness 0.15)
				)
			)
		)
		(property "Value" "FB_120Z_2A_Murata-BLM18PG_0603"
			(at 242.57 78.105 0)
			(effects
				(font
					(size 1.27 1.27)
					(thickness 0.15)
				)
				(justify left bottom)
				(hide yes)
			)
		)
		(property "Footprint" "antmicro-footprints:FB_0603_1608Metric"
			(at 242.57 83.185 0)
			(effects
				(font
					(size 1.27 1.27)
					(thickness 0.15)
				)
				(justify left bottom)
				(hide yes)
			)
		)
		(property "Datasheet" "https://www.murata.com/en-us/products/productdata/8796738650142/ENFA0003.pdf"
			(at 242.57 85.725 0)
			(effects
				(font
					(size 1.27 1.27)
					(thickness 0.15)
				)
				(justify left bottom)
				(hide yes)
			)
		)
		(property "Description" ""
			(at 257.81 75.565 0)
			(effects
				(font
					(size 1.27 1.27)
				)
			)
		)
		(property "Val" "120Z/2A"
			(at 255.3081 72.7003 0)
			(effects
				(font
					(size 1.27 1.27)
				)
			)
		)
		(property "MPN" "BLM18PG121SN1D"
			(at 242.57 88.265 0)
			(effects
				(font
					(size 1.27 1.27)
					(thickness 0.15)
				)
				(justify left bottom)
				(hide yes)
			)
		)
		(property "Manufacturer" "Murata"
			(at 242.57 90.805 0)
			(effects
				(font
					(size 1.27 1.27)
					(thickness 0.15)
				)
				(justify left bottom)
				(hide yes)
			)
		)
		(property "Author" "Antmicro"
			(at 242.57 93.345 0)
			(effects
				(font
					(size 1.27 1.27)
					(thickness 0.15)
				)
				(justify left bottom)
				(hide yes)
			)
		)
		(property "License" "Apache-2.0"
			(at 242.57 95.885 0)
			(effects
				(font
					(size 1.27 1.27)
					(thickness 0.15)
				)
				(justify left bottom)
				(hide yes)
			)
		)
		(pin "1"
		)
		(pin "2"
		)
		(instances
			(project "sodimm-ddr5-tester"
				(path ""
					(reference "FB4")
					(unit 1)
				)
			)
		)
	)
	(symbol
		(lib_id "antmicropower:+3V3")
		(at 74.295 46.99 0)
		(unit 1)
		(exclude_from_sim no)
		(in_bom yes)
		(on_board yes)
		(dnp no)
		(fields_autoplaced yes)
		(property "Reference" "#PWR0240"
			(at 74.295 50.8 0)
			(effects
				(font
					(size 1.27 1.27)
				)
				(hide yes)
			)
		)
		(property "Value" "+3V3"
			(at 71.12 44.45 0)
			(effects
				(font
					(size 1.27 1.27)
					(thickness 0.15)
				)
				(justify left bottom)
			)
		)
		(property "Footprint" ""
			(at 89.535 54.61 0)
			(effects
				(font
					(size 1.27 1.27)
					(thickness 0.15)
				)
				(justify left bottom)
				(hide yes)
			)
		)
		(property "Datasheet" ""
			(at 89.535 57.15 0)
			(effects
				(font
					(size 1.27 1.27)
					(thickness 0.15)
				)
				(justify left bottom)
				(hide yes)
			)
		)
		(property "Description" ""
			(at 74.295 46.99 0)
			(effects
				(font
					(size 1.27 1.27)
				)
			)
		)
		(property "Author" "Antmicro"
			(at 89.535 49.53 0)
			(effects
				(font
					(size 1.27 1.27)
					(thickness 0.15)
				)
				(justify left bottom)
				(hide yes)
			)
		)
		(property "License" "Apache-2.0"
			(at 89.535 52.07 0)
			(effects
				(font
					(size 1.27 1.27)
					(thickness 0.15)
				)
				(justify left bottom)
				(hide yes)
			)
		)
		(pin "1"
		)
		(instances
			(project "sodimm-ddr5-tester"
				(path ""
					(reference "#PWR0240")
					(unit 1)
				)
			)
		)
	)
	(symbol
		(lib_id "antmicropower:GND")
		(at 207.01 62.865 0)
		(mirror y)
		(unit 1)
		(exclude_from_sim no)
		(in_bom yes)
		(on_board yes)
		(dnp no)
		(fields_autoplaced yes)
		(property "Reference" "#PWR0419"
			(at 207.01 69.215 0)
			(effects
				(font
					(size 1.27 1.27)
				)
				(hide yes)
			)
		)
		(property "Value" "GND"
			(at 209.55 64.135 0)
			(effects
				(font
					(size 1.27 1.27)
					(thickness 0.15)
				)
				(justify right)
			)
		)
		(property "Footprint" ""
			(at 198.12 70.485 0)
			(effects
				(font
					(size 1.27 1.27)
					(thickness 0.15)
				)
				(justify left bottom)
				(hide yes)
			)
		)
		(property "Datasheet" ""
			(at 198.12 75.565 0)
			(effects
				(font
					(size 1.27 1.27)
					(thickness 0.15)
				)
				(justify left bottom)
				(hide yes)
			)
		)
		(property "Description" ""
			(at 198.12 78.105 0)
			(effects
				(font
					(size 1.27 1.27)
				)
				(justify left bottom)
				(hide yes)
			)
		)
		(property "Author" "Antmicro"
			(at 198.12 70.485 0)
			(effects
				(font
					(size 1.27 1.27)
					(thickness 0.15)
				)
				(justify left bottom)
				(hide yes)
			)
		)
		(property "License" "Apache-2.0"
			(at 198.12 73.025 0)
			(effects
				(font
					(size 1.27 1.27)
					(thickness 0.15)
				)
				(justify left bottom)
				(hide yes)
			)
		)
		(pin "1"
		)
		(instances
			(project "sodimm-ddr5-tester"
				(path ""
					(reference "#PWR0419")
					(unit 1)
				)
			)
		)
	)
	(symbol
		(lib_id "antmicroCapacitors0402:C_18p_0402")
		(at 121.92 160.02 90)
		(unit 1)
		(exclude_from_sim no)
		(in_bom yes)
		(on_board yes)
		(dnp no)
		(fields_autoplaced yes)
		(property "Reference" "C163"
			(at 124.2441 156.643 90)
			(effects
				(font
					(size 1.27 1.27)
					(thickness 0.15)
				)
				(justify right)
			)
		)
		(property "Value" "C_18p_0402"
			(at 132.08 139.7 0)
			(effects
				(font
					(size 1.27 1.27)
					(thickness 0.15)
				)
				(justify left bottom)
				(hide yes)
			)
		)
		(property "Footprint" "antmicro-footprints:C_0402_1005Metric"
			(at 134.62 139.7 0)
			(effects
				(font
					(size 1.27 1.27)
					(thickness 0.15)
				)
				(justify left bottom)
				(hide yes)
			)
		)
		(property "Datasheet" "https://product.samsungsem.com/mlcc/CL05C180JB51PN.do"
			(at 137.16 139.7 0)
			(effects
				(font
					(size 1.27 1.27)
					(thickness 0.15)
				)
				(justify left bottom)
				(hide yes)
			)
		)
		(property "Description" ""
			(at 121.92 160.02 0)
			(effects
				(font
					(size 1.27 1.27)
				)
			)
		)
		(property "MPN" "CL05C180JB51PNC"
			(at 139.7 139.7 0)
			(effects
				(font
					(size 1.27 1.27)
					(thickness 0.15)
				)
				(justify left bottom)
				(hide yes)
			)
		)
		(property "Manufacturer" "Samsung Electro-Mechanics"
			(at 142.24 139.7 0)
			(effects
				(font
					(size 1.27 1.27)
					(thickness 0.15)
				)
				(justify left bottom)
				(hide yes)
			)
		)
		(property "License" "Apache-2.0"
			(at 144.78 139.7 0)
			(effects
				(font
					(size 1.27 1.27)
					(thickness 0.15)
				)
				(justify left bottom)
				(hide yes)
			)
		)
		(property "Author" "Antmicro"
			(at 147.32 139.7 0)
			(effects
				(font
					(size 1.27 1.27)
					(thickness 0.15)
				)
				(justify left bottom)
				(hide yes)
			)
		)
		(property "Val" "18p"
			(at 124.2441 159.1667 90)
			(effects
				(font
					(size 1.27 1.27)
					(thickness 0.15)
				)
				(justify right)
			)
		)
		(property "Voltage" ""
			(at 149.86 139.7 0)
			(effects
				(font
					(size 1.27 1.27)
				)
				(justify left bottom)
				(hide yes)
			)
		)
		(property "Dielectric" ""
			(at 152.4 139.7 0)
			(effects
				(font
					(size 1.27 1.27)
				)
				(justify left bottom)
				(hide yes)
			)
		)
		(pin "1"
		)
		(pin "2"
		)
		(instances
			(project "sodimm-ddr5-tester"
				(path ""
					(reference "C163")
					(unit 1)
				)
			)
		)
	)
	(symbol
		(lib_id "antmicroResistors0402:R_10k_0402")
		(at 97.155 92.71 180)
		(unit 1)
		(exclude_from_sim no)
		(in_bom yes)
		(on_board yes)
		(dnp no)
		(property "Reference" "R111"
			(at 100.965 91.44 0)
			(effects
				(font
					(size 1.27 1.27)
				)
			)
		)
		(property "Value" "R_10k_0402"
			(at 76.835 80.01 0)
			(effects
				(font
					(size 1.27 1.27)
					(thickness 0.15)
				)
				(justify left bottom)
				(hide yes)
			)
		)
		(property "Footprint" "antmicro-footprints:R_0402_1005Metric"
			(at 76.835 77.47 0)
			(effects
				(font
					(size 1.27 1.27)
					(thickness 0.15)
				)
				(justify left bottom)
				(hide yes)
			)
		)
		(property "Datasheet" "https://www.bourns.com/docs/product-datasheets/cr.pdf"
			(at 76.835 74.93 0)
			(effects
				(font
					(size 1.27 1.27)
					(thickness 0.15)
				)
				(justify left bottom)
				(hide yes)
			)
		)
		(property "Description" ""
			(at 97.155 92.71 0)
			(effects
				(font
					(size 1.27 1.27)
				)
			)
		)
		(property "Manufacturer" "Bourns"
			(at 76.835 69.85 0)
			(effects
				(font
					(size 1.27 1.27)
					(thickness 0.15)
				)
				(justify left bottom)
				(hide yes)
			)
		)
		(property "MPN" "CR0402-FX-1002GLF"
			(at 76.835 72.39 0)
			(effects
				(font
					(size 1.27 1.27)
					(thickness 0.15)
				)
				(justify left bottom)
				(hide yes)
			)
		)
		(property "Val" "10k"
			(at 90.17 91.44 0)
			(effects
				(font
					(size 1.27 1.27)
					(thickness 0.15)
				)
			)
		)
		(property "License" "Apache-2.0"
			(at 76.835 67.31 0)
			(effects
				(font
					(size 1.27 1.27)
					(thickness 0.15)
				)
				(justify left bottom)
				(hide yes)
			)
		)
		(property "Author" "Antmicro"
			(at 76.835 64.77 0)
			(effects
				(font
					(size 1.27 1.27)
					(thickness 0.15)
				)
				(justify left bottom)
				(hide yes)
			)
		)
		(property "Tolerance" "1%"
			(at 76.835 82.55 0)
			(effects
				(font
					(size 1.27 1.27)
				)
				(justify left bottom)
				(hide yes)
			)
		)
		(pin "1"
		)
		(pin "2"
		)
		(instances
			(project "sodimm-ddr5-tester"
				(path ""
					(reference "R111")
					(unit 1)
				)
			)
		)
	)
	(symbol
		(lib_id "antmicroResonators:Resonator_25MHz_ABM8G")
		(at 119.38 153.67 0)
		(mirror y)
		(unit 1)
		(exclude_from_sim no)
		(in_bom yes)
		(on_board yes)
		(dnp no)
		(fields_autoplaced yes)
		(property "Reference" "Y2"
			(at 115.57 147.445 0)
			(effects
				(font
					(size 1.27 1.27)
					(thickness 0.15)
				)
			)
		)
		(property "Value" "Resonator_25MHz_ABM8G"
			(at 104.14 166.37 0)
			(effects
				(font
					(size 1.27 1.27)
					(thickness 0.15)
				)
				(justify left bottom)
				(hide yes)
			)
		)
		(property "Footprint" "antmicro-footprints:Resonator_SMD_Abracon_ABM8G_3.2x2.5mm"
			(at 104.14 168.91 0)
			(effects
				(font
					(size 1.27 1.27)
					(thickness 0.15)
				)
				(justify left bottom)
				(hide yes)
			)
		)
		(property "Datasheet" "https://abracon.com/Resonators/ABM8G.pdf"
			(at 104.14 171.45 0)
			(effects
				(font
					(size 1.27 1.27)
					(thickness 0.15)
				)
				(justify left bottom)
				(hide yes)
			)
		)
		(property "Description" ""
			(at 119.38 153.67 0)
			(effects
				(font
					(size 1.27 1.27)
				)
			)
		)
		(property "MPN" "ABM8G-25.000MHZ-18-D2Y-T3"
			(at 104.14 161.29 0)
			(effects
				(font
					(size 1.27 1.27)
					(thickness 0.15)
				)
				(justify left bottom)
				(hide yes)
			)
		)
		(property "Manufacturer" "Abracon"
			(at 104.14 173.99 0)
			(effects
				(font
					(size 1.27 1.27)
					(thickness 0.15)
				)
				(justify left bottom)
				(hide yes)
			)
		)
		(property "Author" "Antmicro"
			(at 104.14 176.53 0)
			(effects
				(font
					(size 1.27 1.27)
					(thickness 0.15)
				)
				(justify left bottom)
				(hide yes)
			)
		)
		(property "License" "Apache-2.0"
			(at 104.14 179.07 0)
			(effects
				(font
					(size 1.27 1.27)
					(thickness 0.15)
				)
				(justify left bottom)
				(hide yes)
			)
		)
		(property "Val" "25 MHz"
			(at 115.57 149.9687 0)
			(effects
				(font
					(size 1.27 1.27)
					(thickness 0.15)
				)
			)
		)
		(pin "1"
		)
		(pin "2"
		)
		(pin "3"
		)
		(pin "4"
		)
		(instances
			(project "sodimm-ddr5-tester"
				(path ""
					(reference "Y2")
					(unit 1)
				)
			)
		)
	)
	(symbol
		(lib_id "antmicroResistors0402:R_330R_0402")
		(at 288.29 149.86 270)
		(mirror x)
		(unit 1)
		(exclude_from_sim no)
		(in_bom yes)
		(on_board yes)
		(dnp no)
		(property "Reference" "R193"
			(at 292.1 146.558 90)
			(effects
				(font
					(size 1.27 1.27)
				)
			)
		)
		(property "Value" "R_330R_0402"
			(at 275.59 129.54 0)
			(effects
				(font
					(size 1.27 1.27)
					(thickness 0.15)
				)
				(justify left bottom)
				(hide yes)
			)
		)
		(property "Footprint" "antmicro-footprints:R_0402_1005Metric"
			(at 273.05 129.54 0)
			(effects
				(font
					(size 1.27 1.27)
					(thickness 0.15)
				)
				(justify left bottom)
				(hide yes)
			)
		)
		(property "Datasheet" "https://www.bourns.com/docs/product-datasheets/cr.pdf"
			(at 270.51 129.54 0)
			(effects
				(font
					(size 1.27 1.27)
					(thickness 0.15)
				)
				(justify left bottom)
				(hide yes)
			)
		)
		(property "Description" ""
			(at 288.29 149.86 0)
			(effects
				(font
					(size 1.27 1.27)
				)
			)
		)
		(property "Manufacturer" "Bourns"
			(at 265.43 129.54 0)
			(effects
				(font
					(size 1.27 1.27)
					(thickness 0.15)
				)
				(justify left bottom)
				(hide yes)
			)
		)
		(property "MPN" "CR0402-FX-3300GLF"
			(at 267.97 129.54 0)
			(effects
				(font
					(size 1.27 1.27)
					(thickness 0.15)
				)
				(justify left bottom)
				(hide yes)
			)
		)
		(property "Val" "330R"
			(at 292.1 148.59 90)
			(effects
				(font
					(size 1.27 1.27)
					(thickness 0.15)
				)
			)
		)
		(property "License" "Apache-2.0"
			(at 262.89 129.54 0)
			(effects
				(font
					(size 1.27 1.27)
					(thickness 0.15)
				)
				(justify left bottom)
				(hide yes)
			)
		)
		(property "Author" "Antmicro"
			(at 260.35 129.54 0)
			(effects
				(font
					(size 1.27 1.27)
					(thickness 0.15)
				)
				(justify left bottom)
				(hide yes)
			)
		)
		(property "Tolerance" "1%"
			(at 278.13 129.54 0)
			(effects
				(font
					(size 1.27 1.27)
				)
				(justify left bottom)
				(hide yes)
			)
		)
		(pin "1"
		)
		(pin "2"
		)
		(instances
			(project "sodimm-ddr5-tester"
				(path ""
					(reference "R193")
					(unit 1)
				)
			)
		)
	)
	(symbol
		(lib_id "antmicropower:+3V3")
		(at 266.065 260.985 0)
		(unit 1)
		(exclude_from_sim no)
		(in_bom yes)
		(on_board yes)
		(dnp no)
		(property "Reference" "#PWR0252"
			(at 266.065 264.795 0)
			(effects
				(font
					(size 1.27 1.27)
				)
				(hide yes)
			)
		)
		(property "Value" "+3V3"
			(at 262.89 258.445 0)
			(effects
				(font
					(size 1.27 1.27)
					(thickness 0.15)
				)
				(justify left bottom)
			)
		)
		(property "Footprint" ""
			(at 281.305 268.605 0)
			(effects
				(font
					(size 1.27 1.27)
					(thickness 0.15)
				)
				(justify left bottom)
				(hide yes)
			)
		)
		(property "Datasheet" ""
			(at 281.305 271.145 0)
			(effects
				(font
					(size 1.27 1.27)
					(thickness 0.15)
				)
				(justify left bottom)
				(hide yes)
			)
		)
		(property "Description" ""
			(at 266.065 260.985 0)
			(effects
				(font
					(size 1.27 1.27)
				)
			)
		)
		(property "Author" "Antmicro"
			(at 281.305 263.525 0)
			(effects
				(font
					(size 1.27 1.27)
					(thickness 0.15)
				)
				(justify left bottom)
				(hide yes)
			)
		)
		(property "License" "Apache-2.0"
			(at 281.305 266.065 0)
			(effects
				(font
					(size 1.27 1.27)
					(thickness 0.15)
				)
				(justify left bottom)
				(hide yes)
			)
		)
		(pin "1"
		)
		(instances
			(project "sodimm-ddr5-tester"
				(path ""
					(reference "#PWR0252")
					(unit 1)
				)
			)
		)
	)
	(symbol
		(lib_id "antmicroResistors0402:R_10k_0402")
		(at 61.595 217.17 0)
		(mirror y)
		(unit 1)
		(exclude_from_sim no)
		(in_bom no)
		(on_board yes)
		(dnp yes)
		(property "Reference" "R106"
			(at 65.405 215.9 0)
			(effects
				(font
					(size 1.27 1.27)
				)
			)
		)
		(property "Value" "R_10k_0402"
			(at 41.275 229.87 0)
			(effects
				(font
					(size 1.27 1.27)
					(thickness 0.15)
				)
				(justify left bottom)
				(hide yes)
			)
		)
		(property "Footprint" "antmicro-footprints:R_0402_1005Metric"
			(at 41.275 232.41 0)
			(effects
				(font
					(size 1.27 1.27)
					(thickness 0.15)
				)
				(justify left bottom)
				(hide yes)
			)
		)
		(property "Datasheet" "https://www.bourns.com/docs/product-datasheets/cr.pdf"
			(at 41.275 234.95 0)
			(effects
				(font
					(size 1.27 1.27)
					(thickness 0.15)
				)
				(justify left bottom)
				(hide yes)
			)
		)
		(property "Description" ""
			(at 61.595 217.17 0)
			(effects
				(font
					(size 1.27 1.27)
				)
			)
		)
		(property "Manufacturer" "Bourns"
			(at 41.275 240.03 0)
			(effects
				(font
					(size 1.27 1.27)
					(thickness 0.15)
				)
				(justify left bottom)
				(hide yes)
			)
		)
		(property "MPN" "CR0402-FX-1002GLF"
			(at 41.275 237.49 0)
			(effects
				(font
					(size 1.27 1.27)
					(thickness 0.15)
				)
				(justify left bottom)
				(hide yes)
			)
		)
		(property "Val" "10k"
			(at 54.61 215.9 0)
			(effects
				(font
					(size 1.27 1.27)
					(thickness 0.15)
				)
			)
		)
		(property "License" "Apache-2.0"
			(at 41.275 242.57 0)
			(effects
				(font
					(size 1.27 1.27)
					(thickness 0.15)
				)
				(justify left bottom)
				(hide yes)
			)
		)
		(property "Author" "Antmicro"
			(at 41.275 245.11 0)
			(effects
				(font
					(size 1.27 1.27)
					(thickness 0.15)
				)
				(justify left bottom)
				(hide yes)
			)
		)
		(property "Tolerance" "1%"
			(at 41.275 227.33 0)
			(effects
				(font
					(size 1.27 1.27)
				)
				(justify left bottom)
				(hide yes)
			)
		)
		(pin "1"
		)
		(pin "2"
		)
		(instances
			(project "sodimm-ddr5-tester"
				(path ""
					(reference "R106")
					(unit 1)
				)
			)
		)
	)
	(symbol
		(lib_id "antmicroResistors0402:R_10k_0402")
		(at 61.595 213.995 0)
		(mirror y)
		(unit 1)
		(exclude_from_sim no)
		(in_bom no)
		(on_board yes)
		(dnp yes)
		(property "Reference" "R101"
			(at 65.405 212.725 0)
			(effects
				(font
					(size 1.27 1.27)
				)
			)
		)
		(property "Value" "R_10k_0402"
			(at 41.275 226.695 0)
			(effects
				(font
					(size 1.27 1.27)
					(thickness 0.15)
				)
				(justify left bottom)
				(hide yes)
			)
		)
		(property "Footprint" "antmicro-footprints:R_0402_1005Metric"
			(at 41.275 229.235 0)
			(effects
				(font
					(size 1.27 1.27)
					(thickness 0.15)
				)
				(justify left bottom)
				(hide yes)
			)
		)
		(property "Datasheet" "https://www.bourns.com/docs/product-datasheets/cr.pdf"
			(at 41.275 231.775 0)
			(effects
				(font
					(size 1.27 1.27)
					(thickness 0.15)
				)
				(justify left bottom)
				(hide yes)
			)
		)
		(property "Description" ""
			(at 61.595 213.995 0)
			(effects
				(font
					(size 1.27 1.27)
				)
			)
		)
		(property "Manufacturer" "Bourns"
			(at 41.275 236.855 0)
			(effects
				(font
					(size 1.27 1.27)
					(thickness 0.15)
				)
				(justify left bottom)
				(hide yes)
			)
		)
		(property "MPN" "CR0402-FX-1002GLF"
			(at 41.275 234.315 0)
			(effects
				(font
					(size 1.27 1.27)
					(thickness 0.15)
				)
				(justify left bottom)
				(hide yes)
			)
		)
		(property "Val" "10k"
			(at 54.61 212.725 0)
			(effects
				(font
					(size 1.27 1.27)
					(thickness 0.15)
				)
			)
		)
		(property "License" "Apache-2.0"
			(at 41.275 239.395 0)
			(effects
				(font
					(size 1.27 1.27)
					(thickness 0.15)
				)
				(justify left bottom)
				(hide yes)
			)
		)
		(property "Author" "Antmicro"
			(at 41.275 241.935 0)
			(effects
				(font
					(size 1.27 1.27)
					(thickness 0.15)
				)
				(justify left bottom)
				(hide yes)
			)
		)
		(property "Tolerance" "1%"
			(at 41.275 224.155 0)
			(effects
				(font
					(size 1.27 1.27)
				)
				(justify left bottom)
				(hide yes)
			)
		)
		(pin "1"
		)
		(pin "2"
		)
		(instances
			(project "sodimm-ddr5-tester"
				(path ""
					(reference "R101")
					(unit 1)
				)
			)
		)
	)
	(symbol
		(lib_id "antmicropower:GND")
		(at 277.495 266.065 0)
		(unit 1)
		(exclude_from_sim no)
		(in_bom yes)
		(on_board yes)
		(dnp no)
		(fields_autoplaced yes)
		(property "Reference" "#PWR0255"
			(at 277.495 272.415 0)
			(effects
				(font
					(size 1.27 1.27)
				)
				(hide yes)
			)
		)
		(property "Value" "GND"
			(at 279.4 267.335 0)
			(effects
				(font
					(size 1.27 1.27)
					(thickness 0.15)
				)
				(justify left)
			)
		)
		(property "Footprint" ""
			(at 286.385 273.685 0)
			(effects
				(font
					(size 1.27 1.27)
					(thickness 0.15)
				)
				(justify left bottom)
				(hide yes)
			)
		)
		(property "Datasheet" ""
			(at 286.385 278.765 0)
			(effects
				(font
					(size 1.27 1.27)
					(thickness 0.15)
				)
				(justify left bottom)
				(hide yes)
			)
		)
		(property "Description" ""
			(at 286.385 281.305 0)
			(effects
				(font
					(size 1.27 1.27)
				)
				(justify left bottom)
				(hide yes)
			)
		)
		(property "Author" "Antmicro"
			(at 286.385 273.685 0)
			(effects
				(font
					(size 1.27 1.27)
					(thickness 0.15)
				)
				(justify left bottom)
				(hide yes)
			)
		)
		(property "License" "Apache-2.0"
			(at 286.385 276.225 0)
			(effects
				(font
					(size 1.27 1.27)
					(thickness 0.15)
				)
				(justify left bottom)
				(hide yes)
			)
		)
		(pin "1"
		)
		(instances
			(project "sodimm-ddr5-tester"
				(path ""
					(reference "#PWR0255")
					(unit 1)
				)
			)
		)
	)
	(symbol
		(lib_id "antmicroResistors0402:R_10k_0402")
		(at 61.595 219.71 0)
		(mirror y)
		(unit 1)
		(exclude_from_sim no)
		(in_bom yes)
		(on_board yes)
		(dnp no)
		(property "Reference" "R108"
			(at 65.405 218.44 0)
			(effects
				(font
					(size 1.27 1.27)
				)
			)
		)
		(property "Value" "R_10k_0402"
			(at 41.275 232.41 0)
			(effects
				(font
					(size 1.27 1.27)
					(thickness 0.15)
				)
				(justify left bottom)
				(hide yes)
			)
		)
		(property "Footprint" "antmicro-footprints:R_0402_1005Metric"
			(at 41.275 234.95 0)
			(effects
				(font
					(size 1.27 1.27)
					(thickness 0.15)
				)
				(justify left bottom)
				(hide yes)
			)
		)
		(property "Datasheet" "https://www.bourns.com/docs/product-datasheets/cr.pdf"
			(at 41.275 237.49 0)
			(effects
				(font
					(size 1.27 1.27)
					(thickness 0.15)
				)
				(justify left bottom)
				(hide yes)
			)
		)
		(property "Description" ""
			(at 61.595 219.71 0)
			(effects
				(font
					(size 1.27 1.27)
				)
			)
		)
		(property "Manufacturer" "Bourns"
			(at 41.275 242.57 0)
			(effects
				(font
					(size 1.27 1.27)
					(thickness 0.15)
				)
				(justify left bottom)
				(hide yes)
			)
		)
		(property "MPN" "CR0402-FX-1002GLF"
			(at 41.275 240.03 0)
			(effects
				(font
					(size 1.27 1.27)
					(thickness 0.15)
				)
				(justify left bottom)
				(hide yes)
			)
		)
		(property "Val" "10k"
			(at 54.61 218.44 0)
			(effects
				(font
					(size 1.27 1.27)
					(thickness 0.15)
				)
			)
		)
		(property "License" "Apache-2.0"
			(at 41.275 245.11 0)
			(effects
				(font
					(size 1.27 1.27)
					(thickness 0.15)
				)
				(justify left bottom)
				(hide yes)
			)
		)
		(property "Author" "Antmicro"
			(at 41.275 247.65 0)
			(effects
				(font
					(size 1.27 1.27)
					(thickness 0.15)
				)
				(justify left bottom)
				(hide yes)
			)
		)
		(property "Tolerance" "1%"
			(at 41.275 229.87 0)
			(effects
				(font
					(size 1.27 1.27)
				)
				(justify left bottom)
				(hide yes)
			)
		)
		(pin "1"
		)
		(pin "2"
		)
		(instances
			(project "sodimm-ddr5-tester"
				(path ""
					(reference "R108")
					(unit 1)
				)
			)
		)
	)
	(symbol
		(lib_id "antmicropower:GND")
		(at 198.755 83.82 0)
		(unit 1)
		(exclude_from_sim no)
		(in_bom yes)
		(on_board yes)
		(dnp no)
		(fields_autoplaced yes)
		(property "Reference" "#PWR0415"
			(at 198.755 90.17 0)
			(effects
				(font
					(size 1.27 1.27)
				)
				(hide yes)
			)
		)
		(property "Value" "GND"
			(at 200.66 85.09 0)
			(effects
				(font
					(size 1.27 1.27)
					(thickness 0.15)
				)
				(justify left)
			)
		)
		(property "Footprint" ""
			(at 207.645 91.44 0)
			(effects
				(font
					(size 1.27 1.27)
					(thickness 0.15)
				)
				(justify left bottom)
				(hide yes)
			)
		)
		(property "Datasheet" ""
			(at 207.645 96.52 0)
			(effects
				(font
					(size 1.27 1.27)
					(thickness 0.15)
				)
				(justify left bottom)
				(hide yes)
			)
		)
		(property "Description" ""
			(at 207.645 99.06 0)
			(effects
				(font
					(size 1.27 1.27)
				)
				(justify left bottom)
				(hide yes)
			)
		)
		(property "Author" "Antmicro"
			(at 207.645 91.44 0)
			(effects
				(font
					(size 1.27 1.27)
					(thickness 0.15)
				)
				(justify left bottom)
				(hide yes)
			)
		)
		(property "License" "Apache-2.0"
			(at 207.645 93.98 0)
			(effects
				(font
					(size 1.27 1.27)
					(thickness 0.15)
				)
				(justify left bottom)
				(hide yes)
			)
		)
		(pin "1"
		)
		(instances
			(project "sodimm-ddr5-tester"
				(path ""
					(reference "#PWR0415")
					(unit 1)
				)
			)
		)
	)
	(symbol
		(lib_id "antmicropower:+3V3")
		(at 86.36 90.805 0)
		(unit 1)
		(exclude_from_sim no)
		(in_bom yes)
		(on_board yes)
		(dnp no)
		(fields_autoplaced yes)
		(property "Reference" "#PWR0407"
			(at 86.36 94.615 0)
			(effects
				(font
					(size 1.27 1.27)
				)
				(hide yes)
			)
		)
		(property "Value" "+3V3"
			(at 83.185 88.265 0)
			(effects
				(font
					(size 1.27 1.27)
					(thickness 0.15)
				)
				(justify left bottom)
			)
		)
		(property "Footprint" ""
			(at 101.6 98.425 0)
			(effects
				(font
					(size 1.27 1.27)
					(thickness 0.15)
				)
				(justify left bottom)
				(hide yes)
			)
		)
		(property "Datasheet" ""
			(at 101.6 100.965 0)
			(effects
				(font
					(size 1.27 1.27)
					(thickness 0.15)
				)
				(justify left bottom)
				(hide yes)
			)
		)
		(property "Description" ""
			(at 86.36 90.805 0)
			(effects
				(font
					(size 1.27 1.27)
				)
			)
		)
		(property "Author" "Antmicro"
			(at 101.6 93.345 0)
			(effects
				(font
					(size 1.27 1.27)
					(thickness 0.15)
				)
				(justify left bottom)
				(hide yes)
			)
		)
		(property "License" "Apache-2.0"
			(at 101.6 95.885 0)
			(effects
				(font
					(size 1.27 1.27)
					(thickness 0.15)
				)
				(justify left bottom)
				(hide yes)
			)
		)
		(pin "1"
		)
		(instances
			(project "sodimm-ddr5-tester"
				(path ""
					(reference "#PWR0407")
					(unit 1)
				)
			)
		)
	)
	(symbol
		(lib_id "antmicropower:PWR_FLAG")
		(at 120.65 69.85 0)
		(unit 1)
		(exclude_from_sim no)
		(in_bom yes)
		(on_board yes)
		(dnp no)
		(fields_autoplaced yes)
		(property "Reference" "#FLG0104"
			(at 120.65 67.945 0)
			(effects
				(font
					(size 1.27 1.27)
				)
				(hide yes)
			)
		)
		(property "Value" "PWR_FLAG"
			(at 120.65 66.2742 0)
			(effects
				(font
					(size 1.27 1.27)
				)
			)
		)
		(property "Footprint" ""
			(at 120.65 69.85 0)
			(effects
				(font
					(size 1.27 1.27)
				)
				(hide yes)
			)
		)
		(property "Datasheet" ""
			(at 120.65 69.85 0)
			(effects
				(font
					(size 1.27 1.27)
				)
				(hide yes)
			)
		)
		(property "Description" ""
			(at 120.65 69.85 0)
			(effects
				(font
					(size 1.27 1.27)
				)
			)
		)
		(pin "1"
		)
		(instances
			(project "sodimm-ddr5-tester"
				(path ""
					(reference "#FLG0104")
					(unit 1)
				)
			)
		)
	)
	(symbol
		(lib_id "antmicropower:GND")
		(at 248.285 62.865 0)
		(mirror y)
		(unit 1)
		(exclude_from_sim no)
		(in_bom yes)
		(on_board yes)
		(dnp no)
		(fields_autoplaced yes)
		(property "Reference" "#PWR0409"
			(at 248.285 69.215 0)
			(effects
				(font
					(size 1.27 1.27)
				)
				(hide yes)
			)
		)
		(property "Value" "GND"
			(at 250.19 64.135 0)
			(effects
				(font
					(size 1.27 1.27)
					(thickness 0.15)
				)
				(justify right)
			)
		)
		(property "Footprint" ""
			(at 239.395 70.485 0)
			(effects
				(font
					(size 1.27 1.27)
					(thickness 0.15)
				)
				(justify left bottom)
				(hide yes)
			)
		)
		(property "Datasheet" ""
			(at 239.395 75.565 0)
			(effects
				(font
					(size 1.27 1.27)
					(thickness 0.15)
				)
				(justify left bottom)
				(hide yes)
			)
		)
		(property "Description" ""
			(at 239.395 78.105 0)
			(effects
				(font
					(size 1.27 1.27)
				)
				(justify left bottom)
				(hide yes)
			)
		)
		(property "Author" "Antmicro"
			(at 239.395 70.485 0)
			(effects
				(font
					(size 1.27 1.27)
					(thickness 0.15)
				)
				(justify left bottom)
				(hide yes)
			)
		)
		(property "License" "Apache-2.0"
			(at 239.395 73.025 0)
			(effects
				(font
					(size 1.27 1.27)
					(thickness 0.15)
				)
				(justify left bottom)
				(hide yes)
			)
		)
		(pin "1"
		)
		(instances
			(project "sodimm-ddr5-tester"
				(path ""
					(reference "#PWR0409")
					(unit 1)
				)
			)
		)
	)
	(symbol
		(lib_id "antmicropower:GND")
		(at 240.03 62.865 0)
		(mirror y)
		(unit 1)
		(exclude_from_sim no)
		(in_bom yes)
		(on_board yes)
		(dnp no)
		(fields_autoplaced yes)
		(property "Reference" "#PWR0408"
			(at 240.03 69.215 0)
			(effects
				(font
					(size 1.27 1.27)
				)
				(hide yes)
			)
		)
		(property "Value" "GND"
			(at 242.57 64.135 0)
			(effects
				(font
					(size 1.27 1.27)
					(thickness 0.15)
				)
				(justify right)
			)
		)
		(property "Footprint" ""
			(at 231.14 70.485 0)
			(effects
				(font
					(size 1.27 1.27)
					(thickness 0.15)
				)
				(justify left bottom)
				(hide yes)
			)
		)
		(property "Datasheet" ""
			(at 231.14 75.565 0)
			(effects
				(font
					(size 1.27 1.27)
					(thickness 0.15)
				)
				(justify left bottom)
				(hide yes)
			)
		)
		(property "Description" ""
			(at 231.14 78.105 0)
			(effects
				(font
					(size 1.27 1.27)
				)
				(justify left bottom)
				(hide yes)
			)
		)
		(property "Author" "Antmicro"
			(at 231.14 70.485 0)
			(effects
				(font
					(size 1.27 1.27)
					(thickness 0.15)
				)
				(justify left bottom)
				(hide yes)
			)
		)
		(property "License" "Apache-2.0"
			(at 231.14 73.025 0)
			(effects
				(font
					(size 1.27 1.27)
					(thickness 0.15)
				)
				(justify left bottom)
				(hide yes)
			)
		)
		(pin "1"
		)
		(instances
			(project "sodimm-ddr5-tester"
				(path ""
					(reference "#PWR0408")
					(unit 1)
				)
			)
		)
	)
	(symbol
		(lib_id "antmicroCapacitors0402:C_100n_0402")
		(at 266.065 266.065 90)
		(unit 1)
		(exclude_from_sim no)
		(in_bom yes)
		(on_board yes)
		(dnp no)
		(fields_autoplaced yes)
		(property "Reference" "C160"
			(at 268.3891 262.688 90)
			(effects
				(font
					(size 1.27 1.27)
					(thickness 0.15)
				)
				(justify right)
			)
		)
		(property "Value" "C_100n_0402"
			(at 276.225 245.745 0)
			(effects
				(font
					(size 1.27 1.27)
					(thickness 0.15)
				)
				(justify left bottom)
				(hide yes)
			)
		)
		(property "Footprint" "antmicro-footprints:C_0402_1005Metric"
			(at 278.765 245.745 0)
			(effects
				(font
					(size 1.27 1.27)
					(thickness 0.15)
				)
				(justify left bottom)
				(hide yes)
			)
		)
		(property "Datasheet" "https://www.murata.com/products/productdetail?partno=GRM155R61H104KE14%23"
			(at 281.305 245.745 0)
			(effects
				(font
					(size 1.27 1.27)
					(thickness 0.15)
				)
				(justify left bottom)
				(hide yes)
			)
		)
		(property "Description" ""
			(at 266.065 266.065 0)
			(effects
				(font
					(size 1.27 1.27)
				)
			)
		)
		(property "MPN" "GRM155R61H104KE14D"
			(at 283.845 245.745 0)
			(effects
				(font
					(size 1.27 1.27)
					(thickness 0.15)
				)
				(justify left bottom)
				(hide yes)
			)
		)
		(property "Manufacturer" "Murata"
			(at 286.385 245.745 0)
			(effects
				(font
					(size 1.27 1.27)
					(thickness 0.15)
				)
				(justify left bottom)
				(hide yes)
			)
		)
		(property "License" "Apache-2.0"
			(at 288.925 245.745 0)
			(effects
				(font
					(size 1.27 1.27)
					(thickness 0.15)
				)
				(justify left bottom)
				(hide yes)
			)
		)
		(property "Author" "Antmicro"
			(at 291.465 245.745 0)
			(effects
				(font
					(size 1.27 1.27)
					(thickness 0.15)
				)
				(justify left bottom)
				(hide yes)
			)
		)
		(property "Val" "100n"
			(at 268.3891 265.2117 90)
			(effects
				(font
					(size 1.27 1.27)
					(thickness 0.15)
				)
				(justify right)
			)
		)
		(property "Voltage" "50V"
			(at 294.005 245.745 0)
			(effects
				(font
					(size 1.27 1.27)
				)
				(justify left bottom)
				(hide yes)
			)
		)
		(property "Dielectric" "X5R"
			(at 296.545 245.745 0)
			(effects
				(font
					(size 1.27 1.27)
				)
				(justify left bottom)
				(hide yes)
			)
		)
		(pin "1"
		)
		(pin "2"
		)
		(instances
			(project "sodimm-ddr5-tester"
				(path ""
					(reference "C160")
					(unit 1)
				)
			)
		)
	)
	(symbol
		(lib_id "antmicroResistors0402:R_10k_0402")
		(at 61.595 227.965 0)
		(mirror y)
		(unit 1)
		(exclude_from_sim no)
		(in_bom yes)
		(on_board yes)
		(dnp no)
		(property "Reference" "R107"
			(at 65.405 226.695 0)
			(effects
				(font
					(size 1.27 1.27)
				)
			)
		)
		(property "Value" "R_10k_0402"
			(at 41.275 240.665 0)
			(effects
				(font
					(size 1.27 1.27)
					(thickness 0.15)
				)
				(justify left bottom)
				(hide yes)
			)
		)
		(property "Footprint" "antmicro-footprints:R_0402_1005Metric"
			(at 41.275 243.205 0)
			(effects
				(font
					(size 1.27 1.27)
					(thickness 0.15)
				)
				(justify left bottom)
				(hide yes)
			)
		)
		(property "Datasheet" "https://www.bourns.com/docs/product-datasheets/cr.pdf"
			(at 41.275 245.745 0)
			(effects
				(font
					(size 1.27 1.27)
					(thickness 0.15)
				)
				(justify left bottom)
				(hide yes)
			)
		)
		(property "Description" ""
			(at 61.595 227.965 0)
			(effects
				(font
					(size 1.27 1.27)
				)
			)
		)
		(property "Manufacturer" "Bourns"
			(at 41.275 250.825 0)
			(effects
				(font
					(size 1.27 1.27)
					(thickness 0.15)
				)
				(justify left bottom)
				(hide yes)
			)
		)
		(property "MPN" "CR0402-FX-1002GLF"
			(at 41.275 248.285 0)
			(effects
				(font
					(size 1.27 1.27)
					(thickness 0.15)
				)
				(justify left bottom)
				(hide yes)
			)
		)
		(property "Val" "10k"
			(at 54.61 226.695 0)
			(effects
				(font
					(size 1.27 1.27)
					(thickness 0.15)
				)
			)
		)
		(property "License" "Apache-2.0"
			(at 41.275 253.365 0)
			(effects
				(font
					(size 1.27 1.27)
					(thickness 0.15)
				)
				(justify left bottom)
				(hide yes)
			)
		)
		(property "Author" "Antmicro"
			(at 41.275 255.905 0)
			(effects
				(font
					(size 1.27 1.27)
					(thickness 0.15)
				)
				(justify left bottom)
				(hide yes)
			)
		)
		(property "Tolerance" "1%"
			(at 41.275 238.125 0)
			(effects
				(font
					(size 1.27 1.27)
				)
				(justify left bottom)
				(hide yes)
			)
		)
		(pin "1"
		)
		(pin "2"
		)
		(instances
			(project "sodimm-ddr5-tester"
				(path ""
					(reference "R107")
					(unit 1)
				)
			)
		)
	)
)
